FILE_TYPE = MACRO_DRAWING;
SET COLOR_WIRE YELLOW;
SET COLOR_PROP ORANGE;
SET COLOR_DOT WHITE;
SET COLOR_ARC YELLOW;
SET COLOR_BODY GREEN;
SET COLOR_NOTE PURPLE;
SET PROP_DISPLAY VALUE;
SET PAGE_NUMBER P25;
FORCEADD OFFPAGE..2
R 2
(-1250 -275);
FORCEPROP 2 LAST $XR1 93 
J 0
(-1594 -275);
DISPLAY 0.638298 (-1594 -275);
PAINT MONO (-1594 -275);
FORCEPROP 2 LAST $XR0 92 
J 0
(-1504 -275);
DISPLAY 0.638298 (-1504 -275);
PAINT MONO (-1504 -275);
FORCEPROP 2 LAST CDS_LIB standard
J 0
(-1250 -275);
PAINT MONO (-1250 -275);
DISPLAY INVISIBLE (-1250 -275);
FORCEPROP 1 LAST OFFPAGE TRUE
J 2
(-1575 -400);
DISPLAY 0.872340 (-1575 -400);
DISPLAY INVISIBLE (-1575 -400);
FORCEPROP 1 LAST COMMENT_BODY TRUE
J 2
(-1205 -370);
DISPLAY 0.872340 (-1205 -370);
PAINT GREEN (-1205 -370);
DISPLAY INVISIBLE (-1205 -370);
FORCEPROP 2 LAST PATH I1
J 0
(-1200 -200);
DISPLAY 1.021277 (-1200 -200);
DISPLAY INVISIBLE (-1200 -200);
FORCEADD TAP..1
R 2
(-225 -50);
FORCEPROP 3 LASTPIN (-175 -50) SIG_NAME M_F_CPU0_SB_CB<1>
J 0
(-165 -40);
DISPLAY 0.659574 (-165 -40);
PAINT MONO (-165 -40);
DISPLAY INVISIBLE (-165 -40);
FORCEPROP 1 LASTPIN (-175 -50) BN 1
J 2
(-163 -42);
DISPLAY 0.680851 (-163 -42);
PAINT GREEN (-163 -42);
FORCEPROP 2 LAST CDS_LIB standard
J 0
(-225 -50);
DISPLAY INVISIBLE (-225 -50);
FORCEPROP 1 LAST BODY_TYPE PLUMBING
J 2
(-225 0);
DISPLAY 0.872340 (-225 0);
PAINT GREEN (-225 0);
DISPLAY INVISIBLE (-225 0);
FORCEPROP 1 LAST HDL_TAP TRUE
J 2
(-550 -175);
DISPLAY 0.872340 (-550 -175);
DISPLAY INVISIBLE (-550 -175);
FORCEPROP 1 LAST PATH I10
J 2
(-223 -50);
DISPLAY 0.872340 (-223 -50);
PAINT GREEN (-223 -50);
DISPLAY INVISIBLE (-223 -50);
FORCEADD TAP..1
(3200 450);
FORCEPROP 3 LASTPIN (3150 450) SIG_NAME M_F_CPU0_SA_CS_N<1>
J 0
(3160 460);
DISPLAY 0.659574 (3160 460);
PAINT MONO (3160 460);
DISPLAY INVISIBLE (3160 460);
FORCEPROP 1 LASTPIN (3150 450) BN 1
J 0
(3138 458);
DISPLAY 0.680851 (3138 458);
PAINT GREEN (3138 458);
FORCEPROP 2 LAST CDS_LIB standard
J 0
(3200 450);
DISPLAY INVISIBLE (3200 450);
FORCEPROP 1 LAST BODY_TYPE PLUMBING
J 0
(3200 500);
DISPLAY 0.872340 (3200 500);
PAINT GREEN (3200 500);
DISPLAY INVISIBLE (3200 500);
FORCEPROP 1 LAST HDL_TAP TRUE
J 0
(3525 325);
DISPLAY 0.872340 (3525 325);
DISPLAY INVISIBLE (3525 325);
FORCEPROP 1 LAST PATH I100
J 0
(3198 450);
DISPLAY 0.872340 (3198 450);
PAINT GREEN (3198 450);
DISPLAY INVISIBLE (3198 450);
FORCEADD TAP..1
(3200 500);
FORCEPROP 3 LASTPIN (3150 500) SIG_NAME M_F_CPU0_SA_CS_N<2>
J 0
(3160 510);
DISPLAY 0.659574 (3160 510);
PAINT MONO (3160 510);
DISPLAY INVISIBLE (3160 510);
FORCEPROP 1 LASTPIN (3150 500) BN 2
J 0
(3138 508);
DISPLAY 0.680851 (3138 508);
PAINT GREEN (3138 508);
FORCEPROP 2 LAST CDS_LIB standard
J 0
(3200 500);
DISPLAY INVISIBLE (3200 500);
FORCEPROP 1 LAST BODY_TYPE PLUMBING
J 0
(3200 550);
DISPLAY 0.872340 (3200 550);
PAINT GREEN (3200 550);
DISPLAY INVISIBLE (3200 550);
FORCEPROP 1 LAST HDL_TAP TRUE
J 0
(3525 375);
DISPLAY 0.872340 (3525 375);
DISPLAY INVISIBLE (3525 375);
FORCEPROP 1 LAST PATH I101
J 0
(3198 500);
DISPLAY 0.872340 (3198 500);
PAINT GREEN (3198 500);
DISPLAY INVISIBLE (3198 500);
FORCEADD TAP..1
(3200 550);
FORCEPROP 3 LASTPIN (3150 550) SIG_NAME M_F_CPU0_SA_CS_N<3>
J 0
(3160 560);
DISPLAY 0.659574 (3160 560);
PAINT MONO (3160 560);
DISPLAY INVISIBLE (3160 560);
FORCEPROP 1 LASTPIN (3150 550) BN 3
J 0
(3138 558);
DISPLAY 0.680851 (3138 558);
PAINT GREEN (3138 558);
FORCEPROP 2 LAST CDS_LIB standard
J 0
(3200 550);
DISPLAY INVISIBLE (3200 550);
FORCEPROP 1 LAST BODY_TYPE PLUMBING
J 0
(3200 600);
DISPLAY 0.872340 (3200 600);
PAINT GREEN (3200 600);
DISPLAY INVISIBLE (3200 600);
FORCEPROP 1 LAST HDL_TAP TRUE
J 0
(3525 425);
DISPLAY 0.872340 (3525 425);
DISPLAY INVISIBLE (3525 425);
FORCEPROP 1 LAST PATH I102
J 0
(3198 550);
DISPLAY 0.872340 (3198 550);
PAINT GREEN (3198 550);
DISPLAY INVISIBLE (3198 550);
FORCEADD TAP..1
(3200 850);
FORCEPROP 3 LASTPIN (3150 850) SIG_NAME M_F_CPU0_SB_CA<2>
J 0
(3160 860);
DISPLAY 0.659574 (3160 860);
PAINT MONO (3160 860);
DISPLAY INVISIBLE (3160 860);
FORCEPROP 1 LASTPIN (3150 850) BN 2
J 0
(3138 858);
DISPLAY 0.680851 (3138 858);
PAINT GREEN (3138 858);
FORCEPROP 2 LAST CDS_LIB standard
J 0
(3200 850);
DISPLAY INVISIBLE (3200 850);
FORCEPROP 1 LAST BODY_TYPE PLUMBING
J 0
(3200 900);
DISPLAY 0.872340 (3200 900);
PAINT GREEN (3200 900);
DISPLAY INVISIBLE (3200 900);
FORCEPROP 1 LAST HDL_TAP TRUE
J 0
(3525 725);
DISPLAY 0.872340 (3525 725);
DISPLAY INVISIBLE (3525 725);
FORCEPROP 1 LAST PATH I103
J 0
(3198 850);
DISPLAY 0.872340 (3198 850);
PAINT GREEN (3198 850);
DISPLAY INVISIBLE (3198 850);
FORCEADD TAP..1
(3200 750);
FORCEPROP 3 LASTPIN (3150 750) SIG_NAME M_F_CPU0_SB_CA<0>
J 0
(3160 760);
DISPLAY 0.659574 (3160 760);
PAINT MONO (3160 760);
DISPLAY INVISIBLE (3160 760);
FORCEPROP 1 LASTPIN (3150 750) BN 0
J 0
(3138 758);
DISPLAY 0.680851 (3138 758);
PAINT GREEN (3138 758);
FORCEPROP 2 LAST CDS_LIB standard
J 0
(3200 750);
DISPLAY INVISIBLE (3200 750);
FORCEPROP 1 LAST BODY_TYPE PLUMBING
J 0
(3200 800);
DISPLAY 0.872340 (3200 800);
PAINT GREEN (3200 800);
DISPLAY INVISIBLE (3200 800);
FORCEPROP 1 LAST HDL_TAP TRUE
J 0
(3525 625);
DISPLAY 0.872340 (3525 625);
DISPLAY INVISIBLE (3525 625);
FORCEPROP 1 LAST PATH I104
J 0
(3198 750);
DISPLAY 0.872340 (3198 750);
PAINT GREEN (3198 750);
DISPLAY INVISIBLE (3198 750);
FORCEADD TAP..1
(3200 800);
FORCEPROP 3 LASTPIN (3150 800) SIG_NAME M_F_CPU0_SB_CA<1>
J 0
(3160 810);
DISPLAY 0.659574 (3160 810);
PAINT MONO (3160 810);
DISPLAY INVISIBLE (3160 810);
FORCEPROP 1 LASTPIN (3150 800) BN 1
J 0
(3138 808);
DISPLAY 0.680851 (3138 808);
PAINT GREEN (3138 808);
FORCEPROP 2 LAST CDS_LIB standard
J 0
(3200 800);
DISPLAY INVISIBLE (3200 800);
FORCEPROP 1 LAST BODY_TYPE PLUMBING
J 0
(3200 850);
DISPLAY 0.872340 (3200 850);
PAINT GREEN (3200 850);
DISPLAY INVISIBLE (3200 850);
FORCEPROP 1 LAST HDL_TAP TRUE
J 0
(3525 675);
DISPLAY 0.872340 (3525 675);
DISPLAY INVISIBLE (3525 675);
FORCEPROP 1 LAST PATH I105
J 0
(3198 800);
DISPLAY 0.872340 (3198 800);
PAINT GREEN (3198 800);
DISPLAY INVISIBLE (3198 800);
FORCEADD TAP..1
(3200 950);
FORCEPROP 3 LASTPIN (3150 950) SIG_NAME M_F_CPU0_SB_CA<4>
J 0
(3160 960);
DISPLAY 0.659574 (3160 960);
PAINT MONO (3160 960);
DISPLAY INVISIBLE (3160 960);
FORCEPROP 1 LASTPIN (3150 950) BN 4
J 0
(3138 958);
DISPLAY 0.680851 (3138 958);
PAINT GREEN (3138 958);
FORCEPROP 2 LAST CDS_LIB standard
J 0
(3200 950);
DISPLAY INVISIBLE (3200 950);
FORCEPROP 1 LAST BODY_TYPE PLUMBING
J 0
(3200 1000);
DISPLAY 0.872340 (3200 1000);
PAINT GREEN (3200 1000);
DISPLAY INVISIBLE (3200 1000);
FORCEPROP 1 LAST HDL_TAP TRUE
J 0
(3525 825);
DISPLAY 0.872340 (3525 825);
DISPLAY INVISIBLE (3525 825);
FORCEPROP 1 LAST PATH I106
J 0
(3198 950);
DISPLAY 0.872340 (3198 950);
PAINT GREEN (3198 950);
DISPLAY INVISIBLE (3198 950);
FORCEADD TAP..1
(3200 900);
FORCEPROP 3 LASTPIN (3150 900) SIG_NAME M_F_CPU0_SB_CA<3>
J 0
(3160 910);
DISPLAY 0.659574 (3160 910);
PAINT MONO (3160 910);
DISPLAY INVISIBLE (3160 910);
FORCEPROP 1 LASTPIN (3150 900) BN 3
J 0
(3138 908);
DISPLAY 0.680851 (3138 908);
PAINT GREEN (3138 908);
FORCEPROP 2 LAST CDS_LIB standard
J 0
(3200 900);
DISPLAY INVISIBLE (3200 900);
FORCEPROP 1 LAST BODY_TYPE PLUMBING
J 0
(3200 950);
DISPLAY 0.872340 (3200 950);
PAINT GREEN (3200 950);
DISPLAY INVISIBLE (3200 950);
FORCEPROP 1 LAST HDL_TAP TRUE
J 0
(3525 775);
DISPLAY 0.872340 (3525 775);
DISPLAY INVISIBLE (3525 775);
FORCEPROP 1 LAST PATH I107
J 0
(3198 900);
DISPLAY 0.872340 (3198 900);
PAINT GREEN (3198 900);
DISPLAY INVISIBLE (3198 900);
FORCEADD TAP..1
(3200 1050);
FORCEPROP 3 LASTPIN (3150 1050) SIG_NAME M_F_CPU0_SB_CA<6>
J 0
(3160 1060);
DISPLAY 0.659574 (3160 1060);
PAINT MONO (3160 1060);
DISPLAY INVISIBLE (3160 1060);
FORCEPROP 1 LASTPIN (3150 1050) BN 6
J 0
(3138 1058);
DISPLAY 0.680851 (3138 1058);
PAINT GREEN (3138 1058);
FORCEPROP 2 LAST CDS_LIB standard
J 0
(3200 1050);
DISPLAY INVISIBLE (3200 1050);
FORCEPROP 1 LAST BODY_TYPE PLUMBING
J 0
(3200 1100);
DISPLAY 0.872340 (3200 1100);
PAINT GREEN (3200 1100);
DISPLAY INVISIBLE (3200 1100);
FORCEPROP 1 LAST HDL_TAP TRUE
J 0
(3525 925);
DISPLAY 0.872340 (3525 925);
DISPLAY INVISIBLE (3525 925);
FORCEPROP 1 LAST PATH I108
J 0
(3198 1050);
DISPLAY 0.872340 (3198 1050);
PAINT GREEN (3198 1050);
DISPLAY INVISIBLE (3198 1050);
FORCEADD TAP..1
(3200 1000);
FORCEPROP 3 LASTPIN (3150 1000) SIG_NAME M_F_CPU0_SB_CA<5>
J 0
(3160 1010);
DISPLAY 0.659574 (3160 1010);
PAINT MONO (3160 1010);
DISPLAY INVISIBLE (3160 1010);
FORCEPROP 1 LASTPIN (3150 1000) BN 5
J 0
(3138 1008);
DISPLAY 0.680851 (3138 1008);
PAINT GREEN (3138 1008);
FORCEPROP 2 LAST CDS_LIB standard
J 0
(3200 1000);
DISPLAY INVISIBLE (3200 1000);
FORCEPROP 1 LAST BODY_TYPE PLUMBING
J 0
(3200 1050);
DISPLAY 0.872340 (3200 1050);
PAINT GREEN (3200 1050);
DISPLAY INVISIBLE (3200 1050);
FORCEPROP 1 LAST HDL_TAP TRUE
J 0
(3525 875);
DISPLAY 0.872340 (3525 875);
DISPLAY INVISIBLE (3525 875);
FORCEPROP 1 LAST PATH I109
J 0
(3198 1000);
DISPLAY 0.872340 (3198 1000);
PAINT GREEN (3198 1000);
DISPLAY INVISIBLE (3198 1000);
FORCEADD TAP..1
R 2
(-225 -100);
FORCEPROP 3 LASTPIN (-175 -100) SIG_NAME M_F_CPU0_SB_CB<0>
J 0
(-165 -90);
DISPLAY 0.659574 (-165 -90);
PAINT MONO (-165 -90);
DISPLAY INVISIBLE (-165 -90);
FORCEPROP 1 LASTPIN (-175 -100) BN 0
J 2
(-163 -92);
DISPLAY 0.680851 (-163 -92);
PAINT GREEN (-163 -92);
FORCEPROP 2 LAST CDS_LIB standard
J 0
(-225 -100);
DISPLAY INVISIBLE (-225 -100);
FORCEPROP 1 LAST BODY_TYPE PLUMBING
J 2
(-225 -50);
DISPLAY 0.872340 (-225 -50);
PAINT GREEN (-225 -50);
DISPLAY INVISIBLE (-225 -50);
FORCEPROP 1 LAST HDL_TAP TRUE
J 2
(-550 -225);
DISPLAY 0.872340 (-550 -225);
DISPLAY INVISIBLE (-550 -225);
FORCEPROP 1 LAST PATH I11
J 2
(-223 -100);
DISPLAY 0.872340 (-223 -100);
PAINT GREEN (-223 -100);
DISPLAY INVISIBLE (-223 -100);
FORCEADD TAP..1
(3200 1350);
FORCEPROP 3 LASTPIN (3150 1350) SIG_NAME M_F_CPU0_SA_CA<2>
J 0
(3160 1360);
DISPLAY 0.659574 (3160 1360);
PAINT MONO (3160 1360);
DISPLAY INVISIBLE (3160 1360);
FORCEPROP 1 LASTPIN (3150 1350) BN 2
J 0
(3138 1358);
DISPLAY 0.680851 (3138 1358);
PAINT GREEN (3138 1358);
FORCEPROP 2 LAST CDS_LIB standard
J 0
(3200 1350);
DISPLAY INVISIBLE (3200 1350);
FORCEPROP 1 LAST BODY_TYPE PLUMBING
J 0
(3200 1400);
DISPLAY 0.872340 (3200 1400);
PAINT GREEN (3200 1400);
DISPLAY INVISIBLE (3200 1400);
FORCEPROP 1 LAST HDL_TAP TRUE
J 0
(3525 1225);
DISPLAY 0.872340 (3525 1225);
DISPLAY INVISIBLE (3525 1225);
FORCEPROP 1 LAST PATH I110
J 0
(3198 1350);
DISPLAY 0.872340 (3198 1350);
PAINT GREEN (3198 1350);
DISPLAY INVISIBLE (3198 1350);
FORCEADD TAP..1
(3200 1300);
FORCEPROP 3 LASTPIN (3150 1300) SIG_NAME M_F_CPU0_SA_CA<1>
J 0
(3160 1310);
DISPLAY 0.659574 (3160 1310);
PAINT MONO (3160 1310);
DISPLAY INVISIBLE (3160 1310);
FORCEPROP 1 LASTPIN (3150 1300) BN 1
J 0
(3138 1308);
DISPLAY 0.680851 (3138 1308);
PAINT GREEN (3138 1308);
FORCEPROP 2 LAST CDS_LIB standard
J 0
(3200 1300);
DISPLAY INVISIBLE (3200 1300);
FORCEPROP 1 LAST BODY_TYPE PLUMBING
J 0
(3200 1350);
DISPLAY 0.872340 (3200 1350);
PAINT GREEN (3200 1350);
DISPLAY INVISIBLE (3200 1350);
FORCEPROP 1 LAST HDL_TAP TRUE
J 0
(3525 1175);
DISPLAY 0.872340 (3525 1175);
DISPLAY INVISIBLE (3525 1175);
FORCEPROP 1 LAST PATH I111
J 0
(3198 1300);
DISPLAY 0.872340 (3198 1300);
PAINT GREEN (3198 1300);
DISPLAY INVISIBLE (3198 1300);
FORCEADD TAP..1
(3200 1250);
FORCEPROP 3 LASTPIN (3150 1250) SIG_NAME M_F_CPU0_SA_CA<0>
J 0
(3160 1260);
DISPLAY 0.659574 (3160 1260);
PAINT MONO (3160 1260);
DISPLAY INVISIBLE (3160 1260);
FORCEPROP 1 LASTPIN (3150 1250) BN 0
J 0
(3138 1258);
DISPLAY 0.680851 (3138 1258);
PAINT GREEN (3138 1258);
FORCEPROP 2 LAST CDS_LIB standard
J 0
(3200 1250);
DISPLAY INVISIBLE (3200 1250);
FORCEPROP 1 LAST BODY_TYPE PLUMBING
J 0
(3200 1300);
DISPLAY 0.872340 (3200 1300);
PAINT GREEN (3200 1300);
DISPLAY INVISIBLE (3200 1300);
FORCEPROP 1 LAST HDL_TAP TRUE
J 0
(3525 1125);
DISPLAY 0.872340 (3525 1125);
DISPLAY INVISIBLE (3525 1125);
FORCEPROP 1 LAST PATH I112
J 0
(3198 1250);
DISPLAY 0.872340 (3198 1250);
PAINT GREEN (3198 1250);
DISPLAY INVISIBLE (3198 1250);
FORCEADD TAP..1
(3200 1400);
FORCEPROP 3 LASTPIN (3150 1400) SIG_NAME M_F_CPU0_SA_CA<3>
J 0
(3160 1410);
DISPLAY 0.659574 (3160 1410);
PAINT MONO (3160 1410);
DISPLAY INVISIBLE (3160 1410);
FORCEPROP 1 LASTPIN (3150 1400) BN 3
J 0
(3138 1408);
DISPLAY 0.680851 (3138 1408);
PAINT GREEN (3138 1408);
FORCEPROP 2 LAST CDS_LIB standard
J 0
(3200 1400);
DISPLAY INVISIBLE (3200 1400);
FORCEPROP 1 LAST BODY_TYPE PLUMBING
J 0
(3200 1450);
DISPLAY 0.872340 (3200 1450);
PAINT GREEN (3200 1450);
DISPLAY INVISIBLE (3200 1450);
FORCEPROP 1 LAST HDL_TAP TRUE
J 0
(3525 1275);
DISPLAY 0.872340 (3525 1275);
DISPLAY INVISIBLE (3525 1275);
FORCEPROP 1 LAST PATH I113
J 0
(3198 1400);
DISPLAY 0.872340 (3198 1400);
PAINT GREEN (3198 1400);
DISPLAY INVISIBLE (3198 1400);
FORCEADD TAP..1
(3200 1450);
FORCEPROP 3 LASTPIN (3150 1450) SIG_NAME M_F_CPU0_SA_CA<4>
J 0
(3160 1460);
DISPLAY 0.659574 (3160 1460);
PAINT MONO (3160 1460);
DISPLAY INVISIBLE (3160 1460);
FORCEPROP 1 LASTPIN (3150 1450) BN 4
J 0
(3138 1458);
DISPLAY 0.680851 (3138 1458);
PAINT GREEN (3138 1458);
FORCEPROP 2 LAST CDS_LIB standard
J 0
(3200 1450);
DISPLAY INVISIBLE (3200 1450);
FORCEPROP 1 LAST BODY_TYPE PLUMBING
J 0
(3200 1500);
DISPLAY 0.872340 (3200 1500);
PAINT GREEN (3200 1500);
DISPLAY INVISIBLE (3200 1500);
FORCEPROP 1 LAST HDL_TAP TRUE
J 0
(3525 1325);
DISPLAY 0.872340 (3525 1325);
DISPLAY INVISIBLE (3525 1325);
FORCEPROP 1 LAST PATH I114
J 0
(3198 1450);
DISPLAY 0.872340 (3198 1450);
PAINT GREEN (3198 1450);
DISPLAY INVISIBLE (3198 1450);
FORCEADD TAP..1
(3200 1550);
FORCEPROP 3 LASTPIN (3150 1550) SIG_NAME M_F_CPU0_SA_CA<6>
J 0
(3160 1560);
DISPLAY 0.659574 (3160 1560);
PAINT MONO (3160 1560);
DISPLAY INVISIBLE (3160 1560);
FORCEPROP 1 LASTPIN (3150 1550) BN 6
J 0
(3138 1558);
DISPLAY 0.680851 (3138 1558);
PAINT GREEN (3138 1558);
FORCEPROP 2 LAST CDS_LIB standard
J 0
(3200 1550);
DISPLAY INVISIBLE (3200 1550);
FORCEPROP 1 LAST BODY_TYPE PLUMBING
J 0
(3200 1600);
DISPLAY 0.872340 (3200 1600);
PAINT GREEN (3200 1600);
DISPLAY INVISIBLE (3200 1600);
FORCEPROP 1 LAST HDL_TAP TRUE
J 0
(3525 1425);
DISPLAY 0.872340 (3525 1425);
DISPLAY INVISIBLE (3525 1425);
FORCEPROP 1 LAST PATH I115
J 0
(3198 1550);
DISPLAY 0.872340 (3198 1550);
PAINT GREEN (3198 1550);
DISPLAY INVISIBLE (3198 1550);
FORCEADD TAP..1
(3200 1500);
FORCEPROP 3 LASTPIN (3150 1500) SIG_NAME M_F_CPU0_SA_CA<5>
J 0
(3160 1510);
DISPLAY 0.659574 (3160 1510);
PAINT MONO (3160 1510);
DISPLAY INVISIBLE (3160 1510);
FORCEPROP 1 LASTPIN (3150 1500) BN 5
J 0
(3138 1508);
DISPLAY 0.680851 (3138 1508);
PAINT GREEN (3138 1508);
FORCEPROP 2 LAST CDS_LIB standard
J 0
(3200 1500);
DISPLAY INVISIBLE (3200 1500);
FORCEPROP 1 LAST BODY_TYPE PLUMBING
J 0
(3200 1550);
DISPLAY 0.872340 (3200 1550);
PAINT GREEN (3200 1550);
DISPLAY INVISIBLE (3200 1550);
FORCEPROP 1 LAST HDL_TAP TRUE
J 0
(3525 1375);
DISPLAY 0.872340 (3525 1375);
DISPLAY INVISIBLE (3525 1375);
FORCEPROP 1 LAST PATH I116
J 0
(3198 1500);
DISPLAY 0.872340 (3198 1500);
PAINT GREEN (3198 1500);
DISPLAY INVISIBLE (3198 1500);
FORCEADD TAP..1
(3200 1800);
FORCEPROP 3 LASTPIN (3150 1800) SIG_NAME M_F_CPU0_SB_DQS_DN<2>
J 0
(3160 1810);
DISPLAY 0.659574 (3160 1810);
PAINT MONO (3160 1810);
DISPLAY INVISIBLE (3160 1810);
FORCEPROP 1 LASTPIN (3150 1800) BN 2
J 0
(3138 1808);
DISPLAY 0.680851 (3138 1808);
PAINT GREEN (3138 1808);
FORCEPROP 2 LAST CDS_LIB standard
J 0
(3200 1800);
DISPLAY INVISIBLE (3200 1800);
FORCEPROP 1 LAST BODY_TYPE PLUMBING
J 0
(3200 1850);
DISPLAY 0.872340 (3200 1850);
PAINT GREEN (3200 1850);
DISPLAY INVISIBLE (3200 1850);
FORCEPROP 1 LAST HDL_TAP TRUE
J 0
(3525 1675);
DISPLAY 0.872340 (3525 1675);
DISPLAY INVISIBLE (3525 1675);
FORCEPROP 1 LAST PATH I117
J 0
(3198 1800);
DISPLAY 0.872340 (3198 1800);
PAINT GREEN (3198 1800);
DISPLAY INVISIBLE (3198 1800);
FORCEADD TAP..1
(3200 1700);
FORCEPROP 3 LASTPIN (3150 1700) SIG_NAME M_F_CPU0_SB_DQS_DN<0>
J 0
(3160 1710);
DISPLAY 0.659574 (3160 1710);
PAINT MONO (3160 1710);
DISPLAY INVISIBLE (3160 1710);
FORCEPROP 1 LASTPIN (3150 1700) BN 0
J 0
(3138 1708);
DISPLAY 0.680851 (3138 1708);
PAINT GREEN (3138 1708);
FORCEPROP 2 LAST CDS_LIB standard
J 0
(3200 1700);
DISPLAY INVISIBLE (3200 1700);
FORCEPROP 1 LAST BODY_TYPE PLUMBING
J 0
(3200 1750);
DISPLAY 0.872340 (3200 1750);
PAINT GREEN (3200 1750);
DISPLAY INVISIBLE (3200 1750);
FORCEPROP 1 LAST HDL_TAP TRUE
J 0
(3525 1575);
DISPLAY 0.872340 (3525 1575);
DISPLAY INVISIBLE (3525 1575);
FORCEPROP 1 LAST PATH I118
J 0
(3198 1700);
DISPLAY 0.872340 (3198 1700);
PAINT GREEN (3198 1700);
DISPLAY INVISIBLE (3198 1700);
FORCEADD TAP..1
(3200 1850);
FORCEPROP 3 LASTPIN (3150 1850) SIG_NAME M_F_CPU0_SB_DQS_DN<3>
J 0
(3160 1860);
DISPLAY 0.659574 (3160 1860);
PAINT MONO (3160 1860);
DISPLAY INVISIBLE (3160 1860);
FORCEPROP 1 LASTPIN (3150 1850) BN 3
J 0
(3138 1858);
DISPLAY 0.680851 (3138 1858);
PAINT GREEN (3138 1858);
FORCEPROP 2 LAST CDS_LIB standard
J 0
(3200 1850);
DISPLAY INVISIBLE (3200 1850);
FORCEPROP 1 LAST BODY_TYPE PLUMBING
J 0
(3200 1900);
DISPLAY 0.872340 (3200 1900);
PAINT GREEN (3200 1900);
DISPLAY INVISIBLE (3200 1900);
FORCEPROP 1 LAST HDL_TAP TRUE
J 0
(3525 1725);
DISPLAY 0.872340 (3525 1725);
DISPLAY INVISIBLE (3525 1725);
FORCEPROP 1 LAST PATH I119
J 0
(3198 1850);
DISPLAY 0.872340 (3198 1850);
PAINT GREEN (3198 1850);
DISPLAY INVISIBLE (3198 1850);
FORCEADD TAP..1
R 2
(-225 50);
FORCEPROP 3 LASTPIN (-175 50) SIG_NAME M_F_CPU0_SB_CB<3>
J 0
(-165 60);
DISPLAY 0.659574 (-165 60);
PAINT MONO (-165 60);
DISPLAY INVISIBLE (-165 60);
FORCEPROP 1 LASTPIN (-175 50) BN 3
J 2
(-163 58);
DISPLAY 0.680851 (-163 58);
PAINT GREEN (-163 58);
FORCEPROP 2 LAST CDS_LIB standard
J 0
(-225 50);
DISPLAY INVISIBLE (-225 50);
FORCEPROP 1 LAST BODY_TYPE PLUMBING
J 2
(-225 100);
DISPLAY 0.872340 (-225 100);
PAINT GREEN (-225 100);
DISPLAY INVISIBLE (-225 100);
FORCEPROP 1 LAST HDL_TAP TRUE
J 2
(-550 -75);
DISPLAY 0.872340 (-550 -75);
DISPLAY INVISIBLE (-550 -75);
FORCEPROP 1 LAST PATH I12
J 2
(-223 50);
DISPLAY 0.872340 (-223 50);
PAINT GREEN (-223 50);
DISPLAY INVISIBLE (-223 50);
FORCEADD TAP..1
(3200 1750);
FORCEPROP 3 LASTPIN (3150 1750) SIG_NAME M_F_CPU0_SB_DQS_DN<1>
J 0
(3160 1760);
DISPLAY 0.659574 (3160 1760);
PAINT MONO (3160 1760);
DISPLAY INVISIBLE (3160 1760);
FORCEPROP 1 LASTPIN (3150 1750) BN 1
J 0
(3138 1758);
DISPLAY 0.680851 (3138 1758);
PAINT GREEN (3138 1758);
FORCEPROP 2 LAST CDS_LIB standard
J 0
(3200 1750);
DISPLAY INVISIBLE (3200 1750);
FORCEPROP 1 LAST BODY_TYPE PLUMBING
J 0
(3200 1800);
DISPLAY 0.872340 (3200 1800);
PAINT GREEN (3200 1800);
DISPLAY INVISIBLE (3200 1800);
FORCEPROP 1 LAST HDL_TAP TRUE
J 0
(3525 1625);
DISPLAY 0.872340 (3525 1625);
DISPLAY INVISIBLE (3525 1625);
FORCEPROP 1 LAST PATH I120
J 0
(3198 1750);
DISPLAY 0.872340 (3198 1750);
PAINT GREEN (3198 1750);
DISPLAY INVISIBLE (3198 1750);
FORCEADD OFFPAGE..4
(4300 -50);
FORCEPROP 2 LAST $XR0 93 
J 0
(4486 -50);
DISPLAY 0.638298 (4486 -50);
PAINT MONO (4486 -50);
FORCEPROP 2 LAST CDS_LIB standard
J 0
(4300 -50);
PAINT MONO (4300 -50);
DISPLAY INVISIBLE (4300 -50);
FORCEPROP 1 LAST OFFPAGE TRUE
J 0
(4625 -175);
DISPLAY 1.170213 (4625 -175);
PAINT GREEN (4625 -175);
DISPLAY INVISIBLE (4625 -175);
FORCEPROP 1 LAST COMMENT_BODY TRUE
J 0
(4275 -150);
DISPLAY 1.170213 (4275 -150);
PAINT GREEN (4275 -150);
DISPLAY INVISIBLE (4275 -150);
FORCEPROP 2 LAST PATH I121
J 0
(4475 25);
DISPLAY 1.021277 (4475 25);
DISPLAY INVISIBLE (4475 25);
FORCEADD OFFPAGE..4
(4300 -100);
FORCEPROP 2 LAST $XR0 92 
J 0
(4486 -100);
DISPLAY 0.638298 (4486 -100);
PAINT MONO (4486 -100);
FORCEPROP 2 LAST CDS_LIB standard
J 0
(4300 -100);
PAINT MONO (4300 -100);
DISPLAY INVISIBLE (4300 -100);
FORCEPROP 1 LAST OFFPAGE TRUE
J 0
(4625 -225);
DISPLAY 1.170213 (4625 -225);
PAINT GREEN (4625 -225);
DISPLAY INVISIBLE (4625 -225);
FORCEPROP 1 LAST COMMENT_BODY TRUE
J 0
(4275 -200);
DISPLAY 1.170213 (4275 -200);
PAINT GREEN (4275 -200);
DISPLAY INVISIBLE (4275 -200);
FORCEPROP 2 LAST PATH I122
J 0
(4475 -25);
DISPLAY 1.021277 (4475 -25);
DISPLAY INVISIBLE (4475 -25);
FORCEADD OFFPAGE..2
(4300 275);
FORCEPROP 2 LAST $XR1 93 
J 0
(4579 275);
DISPLAY 0.638298 (4579 275);
PAINT MONO (4579 275);
FORCEPROP 2 LAST $XR0 92 
J 0
(4489 275);
DISPLAY 0.638298 (4489 275);
PAINT MONO (4489 275);
FORCEPROP 2 LAST CDS_LIB standard
J 0
(4300 275);
PAINT MONO (4300 275);
DISPLAY INVISIBLE (4300 275);
FORCEPROP 1 LAST OFFPAGE TRUE
J 0
(4625 150);
DISPLAY 1.170213 (4625 150);
PAINT GREEN (4625 150);
DISPLAY INVISIBLE (4625 150);
FORCEPROP 1 LAST COMMENT_BODY TRUE
J 0
(4255 180);
DISPLAY 1.170213 (4255 180);
PAINT GREEN (4255 180);
DISPLAY INVISIBLE (4255 180);
FORCEPROP 2 LAST PATH I123
J 0
(4475 350);
DISPLAY 1.021277 (4475 350);
DISPLAY INVISIBLE (4475 350);
FORCEADD OFFPAGE..2
(4300 575);
FORCEPROP 2 LAST $XR1 93 
J 0
(4579 575);
DISPLAY 0.638298 (4579 575);
PAINT MONO (4579 575);
FORCEPROP 2 LAST $XR0 92 
J 0
(4489 575);
DISPLAY 0.638298 (4489 575);
PAINT MONO (4489 575);
FORCEPROP 2 LAST CDS_LIB standard
J 0
(4300 575);
PAINT MONO (4300 575);
DISPLAY INVISIBLE (4300 575);
FORCEPROP 1 LAST OFFPAGE TRUE
J 0
(4625 450);
DISPLAY 1.170213 (4625 450);
PAINT GREEN (4625 450);
DISPLAY INVISIBLE (4625 450);
FORCEPROP 1 LAST COMMENT_BODY TRUE
J 0
(4255 480);
DISPLAY 1.170213 (4255 480);
PAINT GREEN (4255 480);
DISPLAY INVISIBLE (4255 480);
FORCEPROP 2 LAST PATH I124
J 0
(4475 650);
DISPLAY 1.021277 (4475 650);
DISPLAY INVISIBLE (4475 650);
FORCEADD OFFPAGE..2
(4300 700);
FORCEPROP 2 LAST $XR1 93 
J 0
(4579 700);
DISPLAY 0.638298 (4579 700);
PAINT MONO (4579 700);
FORCEPROP 2 LAST $XR0 92 
J 0
(4489 700);
DISPLAY 0.638298 (4489 700);
PAINT MONO (4489 700);
FORCEPROP 2 LAST CDS_LIB standard
J 0
(4300 700);
PAINT MONO (4300 700);
DISPLAY INVISIBLE (4300 700);
FORCEPROP 1 LAST OFFPAGE TRUE
J 0
(4625 575);
DISPLAY 1.170213 (4625 575);
PAINT GREEN (4625 575);
DISPLAY INVISIBLE (4625 575);
FORCEPROP 1 LAST COMMENT_BODY TRUE
J 0
(4255 605);
DISPLAY 1.170213 (4255 605);
PAINT GREEN (4255 605);
DISPLAY INVISIBLE (4255 605);
FORCEPROP 2 LAST PATH I125
J 0
(4475 775);
DISPLAY 1.021277 (4475 775);
DISPLAY INVISIBLE (4475 775);
FORCEADD OFFPAGE..3
(4300 1075);
FORCEPROP 2 LAST $XR1 93 
J 0
(4604 1075);
DISPLAY 0.638298 (4604 1075);
PAINT MONO (4604 1075);
FORCEPROP 2 LAST $XR0 92 
J 0
(4514 1075);
DISPLAY 0.638298 (4514 1075);
PAINT MONO (4514 1075);
FORCEPROP 2 LAST CDS_LIB standard
J 2
(4300 1075);
DISPLAY INVISIBLE (4300 1075);
FORCEPROP 1 LAST OFFPAGE TRUE
J 0
(4625 950);
DISPLAY 0.872340 (4625 950);
DISPLAY INVISIBLE (4625 950);
FORCEPROP 1 LAST COMMENT_BODY TRUE
J 0
(4250 975);
DISPLAY 0.872340 (4250 975);
PAINT GREEN (4250 975);
DISPLAY INVISIBLE (4250 975);
FORCEPROP 2 LAST PATH I126
J 0
(4500 1150);
DISPLAY 1.021277 (4500 1150);
DISPLAY INVISIBLE (4500 1150);
FORCEADD OFFPAGE..2
(4300 1200);
FORCEPROP 2 LAST $XR1 93 
J 0
(4579 1200);
DISPLAY 0.638298 (4579 1200);
PAINT MONO (4579 1200);
FORCEPROP 2 LAST $XR0 92 
J 0
(4489 1200);
DISPLAY 0.638298 (4489 1200);
PAINT MONO (4489 1200);
FORCEPROP 2 LAST CDS_LIB standard
J 0
(4300 1200);
PAINT MONO (4300 1200);
DISPLAY INVISIBLE (4300 1200);
FORCEPROP 1 LAST OFFPAGE TRUE
J 0
(4625 1075);
DISPLAY 1.170213 (4625 1075);
PAINT GREEN (4625 1075);
DISPLAY INVISIBLE (4625 1075);
FORCEPROP 1 LAST COMMENT_BODY TRUE
J 0
(4255 1105);
DISPLAY 1.170213 (4255 1105);
PAINT GREEN (4255 1105);
DISPLAY INVISIBLE (4255 1105);
FORCEPROP 2 LAST PATH I127
J 0
(4475 1275);
DISPLAY 1.021277 (4475 1275);
DISPLAY INVISIBLE (4475 1275);
FORCEADD OFFPAGE..3
(4300 1575);
FORCEPROP 2 LAST $XR1 93 
J 0
(4604 1575);
DISPLAY 0.638298 (4604 1575);
PAINT MONO (4604 1575);
FORCEPROP 2 LAST $XR0 92 
J 0
(4514 1575);
DISPLAY 0.638298 (4514 1575);
PAINT MONO (4514 1575);
FORCEPROP 2 LAST CDS_LIB standard
J 2
(4300 1575);
DISPLAY INVISIBLE (4300 1575);
FORCEPROP 1 LAST OFFPAGE TRUE
J 0
(4625 1450);
DISPLAY 0.872340 (4625 1450);
DISPLAY INVISIBLE (4625 1450);
FORCEPROP 1 LAST COMMENT_BODY TRUE
J 0
(4250 1475);
DISPLAY 0.872340 (4250 1475);
PAINT GREEN (4250 1475);
DISPLAY INVISIBLE (4250 1475);
FORCEPROP 2 LAST PATH I128
J 0
(4500 1650);
DISPLAY 1.021277 (4500 1650);
DISPLAY INVISIBLE (4500 1650);
FORCEADD TAP..1
(3200 2150);
FORCEPROP 3 LASTPIN (3150 2150) SIG_NAME M_F_CPU0_SB_DQS_DN<9>
J 0
(3160 2160);
DISPLAY 0.659574 (3160 2160);
PAINT MONO (3160 2160);
DISPLAY INVISIBLE (3160 2160);
FORCEPROP 1 LASTPIN (3150 2150) BN 9
J 0
(3138 2158);
DISPLAY 0.680851 (3138 2158);
PAINT GREEN (3138 2158);
FORCEPROP 2 LAST CDS_LIB standard
J 0
(3200 2150);
DISPLAY INVISIBLE (3200 2150);
FORCEPROP 1 LAST BODY_TYPE PLUMBING
J 0
(3200 2200);
DISPLAY 0.872340 (3200 2200);
PAINT GREEN (3200 2200);
DISPLAY INVISIBLE (3200 2200);
FORCEPROP 1 LAST HDL_TAP TRUE
J 0
(3525 2025);
DISPLAY 0.872340 (3525 2025);
DISPLAY INVISIBLE (3525 2025);
FORCEPROP 1 LAST PATH I129
J 0
(3198 2150);
DISPLAY 0.872340 (3198 2150);
PAINT GREEN (3198 2150);
DISPLAY INVISIBLE (3198 2150);
FORCEADD TAP..1
R 2
(-225 0);
FORCEPROP 3 LASTPIN (-175 0) SIG_NAME M_F_CPU0_SB_CB<2>
J 0
(-165 10);
DISPLAY 0.659574 (-165 10);
PAINT MONO (-165 10);
DISPLAY INVISIBLE (-165 10);
FORCEPROP 1 LASTPIN (-175 0) BN 2
J 2
(-163 8);
DISPLAY 0.680851 (-163 8);
PAINT GREEN (-163 8);
FORCEPROP 2 LAST CDS_LIB standard
J 0
(-225 0);
DISPLAY INVISIBLE (-225 0);
FORCEPROP 1 LAST BODY_TYPE PLUMBING
J 2
(-225 50);
DISPLAY 0.872340 (-225 50);
PAINT GREEN (-225 50);
DISPLAY INVISIBLE (-225 50);
FORCEPROP 1 LAST HDL_TAP TRUE
J 2
(-550 -125);
DISPLAY 0.872340 (-550 -125);
DISPLAY INVISIBLE (-550 -125);
FORCEPROP 1 LAST PATH I13
J 2
(-223 0);
DISPLAY 0.872340 (-223 0);
PAINT GREEN (-223 0);
DISPLAY INVISIBLE (-223 0);
FORCEADD TAP..1
(3200 2100);
FORCEPROP 3 LASTPIN (3150 2100) SIG_NAME M_F_CPU0_SB_DQS_DN<8>
J 0
(3160 2110);
DISPLAY 0.659574 (3160 2110);
PAINT MONO (3160 2110);
DISPLAY INVISIBLE (3160 2110);
FORCEPROP 1 LASTPIN (3150 2100) BN 8
J 0
(3138 2108);
DISPLAY 0.680851 (3138 2108);
PAINT GREEN (3138 2108);
FORCEPROP 2 LAST CDS_LIB standard
J 0
(3200 2100);
DISPLAY INVISIBLE (3200 2100);
FORCEPROP 1 LAST BODY_TYPE PLUMBING
J 0
(3200 2150);
DISPLAY 0.872340 (3200 2150);
PAINT GREEN (3200 2150);
DISPLAY INVISIBLE (3200 2150);
FORCEPROP 1 LAST HDL_TAP TRUE
J 0
(3525 1975);
DISPLAY 0.872340 (3525 1975);
DISPLAY INVISIBLE (3525 1975);
FORCEPROP 1 LAST PATH I130
J 0
(3198 2100);
DISPLAY 0.872340 (3198 2100);
PAINT GREEN (3198 2100);
DISPLAY INVISIBLE (3198 2100);
FORCEADD TAP..1
(3200 2050);
FORCEPROP 3 LASTPIN (3150 2050) SIG_NAME M_F_CPU0_SB_DQS_DN<7>
J 0
(3160 2060);
DISPLAY 0.659574 (3160 2060);
PAINT MONO (3160 2060);
DISPLAY INVISIBLE (3160 2060);
FORCEPROP 1 LASTPIN (3150 2050) BN 7
J 0
(3138 2058);
DISPLAY 0.680851 (3138 2058);
PAINT GREEN (3138 2058);
FORCEPROP 2 LAST CDS_LIB standard
J 0
(3200 2050);
DISPLAY INVISIBLE (3200 2050);
FORCEPROP 1 LAST BODY_TYPE PLUMBING
J 0
(3200 2100);
DISPLAY 0.872340 (3200 2100);
PAINT GREEN (3200 2100);
DISPLAY INVISIBLE (3200 2100);
FORCEPROP 1 LAST HDL_TAP TRUE
J 0
(3525 1925);
DISPLAY 0.872340 (3525 1925);
DISPLAY INVISIBLE (3525 1925);
FORCEPROP 1 LAST PATH I131
J 0
(3198 2050);
DISPLAY 0.872340 (3198 2050);
PAINT GREEN (3198 2050);
DISPLAY INVISIBLE (3198 2050);
FORCEADD TAP..1
(3200 2000);
FORCEPROP 3 LASTPIN (3150 2000) SIG_NAME M_F_CPU0_SB_DQS_DN<6>
J 0
(3160 2010);
DISPLAY 0.659574 (3160 2010);
PAINT MONO (3160 2010);
DISPLAY INVISIBLE (3160 2010);
FORCEPROP 1 LASTPIN (3150 2000) BN 6
J 0
(3138 2008);
DISPLAY 0.680851 (3138 2008);
PAINT GREEN (3138 2008);
FORCEPROP 2 LAST CDS_LIB standard
J 0
(3200 2000);
DISPLAY INVISIBLE (3200 2000);
FORCEPROP 1 LAST BODY_TYPE PLUMBING
J 0
(3200 2050);
DISPLAY 0.872340 (3200 2050);
PAINT GREEN (3200 2050);
DISPLAY INVISIBLE (3200 2050);
FORCEPROP 1 LAST HDL_TAP TRUE
J 0
(3525 1875);
DISPLAY 0.872340 (3525 1875);
DISPLAY INVISIBLE (3525 1875);
FORCEPROP 1 LAST PATH I132
J 0
(3198 2000);
DISPLAY 0.872340 (3198 2000);
PAINT GREEN (3198 2000);
DISPLAY INVISIBLE (3198 2000);
FORCEADD TAP..1
(3200 1950);
FORCEPROP 3 LASTPIN (3150 1950) SIG_NAME M_F_CPU0_SB_DQS_DN<5>
J 0
(3160 1960);
DISPLAY 0.659574 (3160 1960);
PAINT MONO (3160 1960);
DISPLAY INVISIBLE (3160 1960);
FORCEPROP 1 LASTPIN (3150 1950) BN 5
J 0
(3138 1958);
DISPLAY 0.680851 (3138 1958);
PAINT GREEN (3138 1958);
FORCEPROP 2 LAST CDS_LIB standard
J 0
(3200 1950);
DISPLAY INVISIBLE (3200 1950);
FORCEPROP 1 LAST BODY_TYPE PLUMBING
J 0
(3200 2000);
DISPLAY 0.872340 (3200 2000);
PAINT GREEN (3200 2000);
DISPLAY INVISIBLE (3200 2000);
FORCEPROP 1 LAST HDL_TAP TRUE
J 0
(3525 1825);
DISPLAY 0.872340 (3525 1825);
DISPLAY INVISIBLE (3525 1825);
FORCEPROP 1 LAST PATH I133
J 0
(3198 1950);
DISPLAY 0.872340 (3198 1950);
PAINT GREEN (3198 1950);
DISPLAY INVISIBLE (3198 1950);
FORCEADD TAP..1
(3200 1900);
FORCEPROP 3 LASTPIN (3150 1900) SIG_NAME M_F_CPU0_SB_DQS_DN<4>
J 0
(3160 1910);
DISPLAY 0.659574 (3160 1910);
PAINT MONO (3160 1910);
DISPLAY INVISIBLE (3160 1910);
FORCEPROP 1 LASTPIN (3150 1900) BN 4
J 0
(3138 1908);
DISPLAY 0.680851 (3138 1908);
PAINT GREEN (3138 1908);
FORCEPROP 2 LAST CDS_LIB standard
J 0
(3200 1900);
DISPLAY INVISIBLE (3200 1900);
FORCEPROP 1 LAST BODY_TYPE PLUMBING
J 0
(3200 1950);
DISPLAY 0.872340 (3200 1950);
PAINT GREEN (3200 1950);
DISPLAY INVISIBLE (3200 1950);
FORCEPROP 1 LAST HDL_TAP TRUE
J 0
(3525 1775);
DISPLAY 0.872340 (3525 1775);
DISPLAY INVISIBLE (3525 1775);
FORCEPROP 1 LAST PATH I134
J 0
(3198 1900);
DISPLAY 0.872340 (3198 1900);
PAINT GREEN (3198 1900);
DISPLAY INVISIBLE (3198 1900);
FORCEADD TAP..1
(3200 2300);
FORCEPROP 3 LASTPIN (3150 2300) SIG_NAME M_F_CPU0_SB_DQS_DP<1>
J 0
(3160 2310);
DISPLAY 0.659574 (3160 2310);
PAINT MONO (3160 2310);
DISPLAY INVISIBLE (3160 2310);
FORCEPROP 1 LASTPIN (3150 2300) BN 1
J 0
(3138 2308);
DISPLAY 0.680851 (3138 2308);
PAINT GREEN (3138 2308);
FORCEPROP 2 LAST CDS_LIB standard
J 0
(3200 2300);
DISPLAY INVISIBLE (3200 2300);
FORCEPROP 1 LAST BODY_TYPE PLUMBING
J 0
(3200 2350);
DISPLAY 0.872340 (3200 2350);
PAINT GREEN (3200 2350);
DISPLAY INVISIBLE (3200 2350);
FORCEPROP 1 LAST HDL_TAP TRUE
J 0
(3525 2175);
DISPLAY 0.872340 (3525 2175);
DISPLAY INVISIBLE (3525 2175);
FORCEPROP 1 LAST PATH I135
J 0
(3198 2300);
DISPLAY 0.872340 (3198 2300);
PAINT GREEN (3198 2300);
DISPLAY INVISIBLE (3198 2300);
FORCEADD TAP..1
(3200 2250);
FORCEPROP 3 LASTPIN (3150 2250) SIG_NAME M_F_CPU0_SB_DQS_DP<0>
J 0
(3160 2260);
DISPLAY 0.659574 (3160 2260);
PAINT MONO (3160 2260);
DISPLAY INVISIBLE (3160 2260);
FORCEPROP 1 LASTPIN (3150 2250) BN 0
J 0
(3138 2258);
DISPLAY 0.680851 (3138 2258);
PAINT GREEN (3138 2258);
FORCEPROP 2 LAST CDS_LIB standard
J 0
(3200 2250);
DISPLAY INVISIBLE (3200 2250);
FORCEPROP 1 LAST BODY_TYPE PLUMBING
J 0
(3200 2300);
DISPLAY 0.872340 (3200 2300);
PAINT GREEN (3200 2300);
DISPLAY INVISIBLE (3200 2300);
FORCEPROP 1 LAST HDL_TAP TRUE
J 0
(3525 2125);
DISPLAY 0.872340 (3525 2125);
DISPLAY INVISIBLE (3525 2125);
FORCEPROP 1 LAST PATH I136
J 0
(3198 2250);
DISPLAY 0.872340 (3198 2250);
PAINT GREEN (3198 2250);
DISPLAY INVISIBLE (3198 2250);
FORCEADD TAP..1
(3200 2350);
FORCEPROP 3 LASTPIN (3150 2350) SIG_NAME M_F_CPU0_SB_DQS_DP<2>
J 0
(3160 2360);
DISPLAY 0.659574 (3160 2360);
PAINT MONO (3160 2360);
DISPLAY INVISIBLE (3160 2360);
FORCEPROP 1 LASTPIN (3150 2350) BN 2
J 0
(3138 2358);
DISPLAY 0.680851 (3138 2358);
PAINT GREEN (3138 2358);
FORCEPROP 2 LAST CDS_LIB standard
J 0
(3200 2350);
DISPLAY INVISIBLE (3200 2350);
FORCEPROP 1 LAST BODY_TYPE PLUMBING
J 0
(3200 2400);
DISPLAY 0.872340 (3200 2400);
PAINT GREEN (3200 2400);
DISPLAY INVISIBLE (3200 2400);
FORCEPROP 1 LAST HDL_TAP TRUE
J 0
(3525 2225);
DISPLAY 0.872340 (3525 2225);
DISPLAY INVISIBLE (3525 2225);
FORCEPROP 1 LAST PATH I137
J 0
(3198 2350);
DISPLAY 0.872340 (3198 2350);
PAINT GREEN (3198 2350);
DISPLAY INVISIBLE (3198 2350);
FORCEADD TAP..1
(3200 2400);
FORCEPROP 3 LASTPIN (3150 2400) SIG_NAME M_F_CPU0_SB_DQS_DP<3>
J 0
(3160 2410);
DISPLAY 0.659574 (3160 2410);
PAINT MONO (3160 2410);
DISPLAY INVISIBLE (3160 2410);
FORCEPROP 1 LASTPIN (3150 2400) BN 3
J 0
(3138 2408);
DISPLAY 0.680851 (3138 2408);
PAINT GREEN (3138 2408);
FORCEPROP 2 LAST CDS_LIB standard
J 0
(3200 2400);
DISPLAY INVISIBLE (3200 2400);
FORCEPROP 1 LAST BODY_TYPE PLUMBING
J 0
(3200 2450);
DISPLAY 0.872340 (3200 2450);
PAINT GREEN (3200 2450);
DISPLAY INVISIBLE (3200 2450);
FORCEPROP 1 LAST HDL_TAP TRUE
J 0
(3525 2275);
DISPLAY 0.872340 (3525 2275);
DISPLAY INVISIBLE (3525 2275);
FORCEPROP 1 LAST PATH I138
J 0
(3198 2400);
DISPLAY 0.872340 (3198 2400);
PAINT GREEN (3198 2400);
DISPLAY INVISIBLE (3198 2400);
FORCEADD TAP..1
(3200 2500);
FORCEPROP 3 LASTPIN (3150 2500) SIG_NAME M_F_CPU0_SB_DQS_DP<5>
J 0
(3160 2510);
DISPLAY 0.659574 (3160 2510);
PAINT MONO (3160 2510);
DISPLAY INVISIBLE (3160 2510);
FORCEPROP 1 LASTPIN (3150 2500) BN 5
J 0
(3138 2508);
DISPLAY 0.680851 (3138 2508);
PAINT GREEN (3138 2508);
FORCEPROP 2 LAST CDS_LIB standard
J 0
(3200 2500);
DISPLAY INVISIBLE (3200 2500);
FORCEPROP 1 LAST BODY_TYPE PLUMBING
J 0
(3200 2550);
DISPLAY 0.872340 (3200 2550);
PAINT GREEN (3200 2550);
DISPLAY INVISIBLE (3200 2550);
FORCEPROP 1 LAST HDL_TAP TRUE
J 0
(3525 2375);
DISPLAY 0.872340 (3525 2375);
DISPLAY INVISIBLE (3525 2375);
FORCEPROP 1 LAST PATH I139
J 0
(3198 2500);
DISPLAY 0.872340 (3198 2500);
PAINT GREEN (3198 2500);
DISPLAY INVISIBLE (3198 2500);
FORCEADD TAP..1
R 2
(-225 100);
FORCEPROP 3 LASTPIN (-175 100) SIG_NAME M_F_CPU0_SB_CB<4>
J 0
(-165 110);
DISPLAY 0.659574 (-165 110);
PAINT MONO (-165 110);
DISPLAY INVISIBLE (-165 110);
FORCEPROP 1 LASTPIN (-175 100) BN 4
J 2
(-163 108);
DISPLAY 0.680851 (-163 108);
PAINT GREEN (-163 108);
FORCEPROP 2 LAST CDS_LIB standard
J 0
(-225 100);
DISPLAY INVISIBLE (-225 100);
FORCEPROP 1 LAST BODY_TYPE PLUMBING
J 2
(-225 150);
DISPLAY 0.872340 (-225 150);
PAINT GREEN (-225 150);
DISPLAY INVISIBLE (-225 150);
FORCEPROP 1 LAST HDL_TAP TRUE
J 2
(-550 -25);
DISPLAY 0.872340 (-550 -25);
DISPLAY INVISIBLE (-550 -25);
FORCEPROP 1 LAST PATH I14
J 2
(-223 100);
DISPLAY 0.872340 (-223 100);
PAINT GREEN (-223 100);
DISPLAY INVISIBLE (-223 100);
FORCEADD TAP..1
(3200 2450);
FORCEPROP 3 LASTPIN (3150 2450) SIG_NAME M_F_CPU0_SB_DQS_DP<4>
J 0
(3160 2460);
DISPLAY 0.659574 (3160 2460);
PAINT MONO (3160 2460);
DISPLAY INVISIBLE (3160 2460);
FORCEPROP 1 LASTPIN (3150 2450) BN 4
J 0
(3138 2458);
DISPLAY 0.680851 (3138 2458);
PAINT GREEN (3138 2458);
FORCEPROP 2 LAST CDS_LIB standard
J 0
(3200 2450);
DISPLAY INVISIBLE (3200 2450);
FORCEPROP 1 LAST BODY_TYPE PLUMBING
J 0
(3200 2500);
DISPLAY 0.872340 (3200 2500);
PAINT GREEN (3200 2500);
DISPLAY INVISIBLE (3200 2500);
FORCEPROP 1 LAST HDL_TAP TRUE
J 0
(3525 2325);
DISPLAY 0.872340 (3525 2325);
DISPLAY INVISIBLE (3525 2325);
FORCEPROP 1 LAST PATH I140
J 0
(3198 2450);
DISPLAY 0.872340 (3198 2450);
PAINT GREEN (3198 2450);
DISPLAY INVISIBLE (3198 2450);
FORCEADD TAP..1
(3200 2550);
FORCEPROP 3 LASTPIN (3150 2550) SIG_NAME M_F_CPU0_SB_DQS_DP<6>
J 0
(3160 2560);
DISPLAY 0.659574 (3160 2560);
PAINT MONO (3160 2560);
DISPLAY INVISIBLE (3160 2560);
FORCEPROP 1 LASTPIN (3150 2550) BN 6
J 0
(3138 2558);
DISPLAY 0.680851 (3138 2558);
PAINT GREEN (3138 2558);
FORCEPROP 2 LAST CDS_LIB standard
J 0
(3200 2550);
DISPLAY INVISIBLE (3200 2550);
FORCEPROP 1 LAST BODY_TYPE PLUMBING
J 0
(3200 2600);
DISPLAY 0.872340 (3200 2600);
PAINT GREEN (3200 2600);
DISPLAY INVISIBLE (3200 2600);
FORCEPROP 1 LAST HDL_TAP TRUE
J 0
(3525 2425);
DISPLAY 0.872340 (3525 2425);
DISPLAY INVISIBLE (3525 2425);
FORCEPROP 1 LAST PATH I141
J 0
(3198 2550);
DISPLAY 0.872340 (3198 2550);
PAINT GREEN (3198 2550);
DISPLAY INVISIBLE (3198 2550);
FORCEADD TAP..1
(3200 2600);
FORCEPROP 3 LASTPIN (3150 2600) SIG_NAME M_F_CPU0_SB_DQS_DP<7>
J 0
(3160 2610);
DISPLAY 0.659574 (3160 2610);
PAINT MONO (3160 2610);
DISPLAY INVISIBLE (3160 2610);
FORCEPROP 1 LASTPIN (3150 2600) BN 7
J 0
(3138 2608);
DISPLAY 0.680851 (3138 2608);
PAINT GREEN (3138 2608);
FORCEPROP 2 LAST CDS_LIB standard
J 0
(3200 2600);
DISPLAY INVISIBLE (3200 2600);
FORCEPROP 1 LAST BODY_TYPE PLUMBING
J 0
(3200 2650);
DISPLAY 0.872340 (3200 2650);
PAINT GREEN (3200 2650);
DISPLAY INVISIBLE (3200 2650);
FORCEPROP 1 LAST HDL_TAP TRUE
J 0
(3525 2475);
DISPLAY 0.872340 (3525 2475);
DISPLAY INVISIBLE (3525 2475);
FORCEPROP 1 LAST PATH I142
J 0
(3198 2600);
DISPLAY 0.872340 (3198 2600);
PAINT GREEN (3198 2600);
DISPLAY INVISIBLE (3198 2600);
FORCEADD TAP..1
(3200 2650);
FORCEPROP 3 LASTPIN (3150 2650) SIG_NAME M_F_CPU0_SB_DQS_DP<8>
J 0
(3160 2660);
DISPLAY 0.659574 (3160 2660);
PAINT MONO (3160 2660);
DISPLAY INVISIBLE (3160 2660);
FORCEPROP 1 LASTPIN (3150 2650) BN 8
J 0
(3138 2658);
DISPLAY 0.680851 (3138 2658);
PAINT GREEN (3138 2658);
FORCEPROP 2 LAST CDS_LIB standard
J 0
(3200 2650);
DISPLAY INVISIBLE (3200 2650);
FORCEPROP 1 LAST BODY_TYPE PLUMBING
J 0
(3200 2700);
DISPLAY 0.872340 (3200 2700);
PAINT GREEN (3200 2700);
DISPLAY INVISIBLE (3200 2700);
FORCEPROP 1 LAST HDL_TAP TRUE
J 0
(3525 2525);
DISPLAY 0.872340 (3525 2525);
DISPLAY INVISIBLE (3525 2525);
FORCEPROP 1 LAST PATH I143
J 0
(3198 2650);
DISPLAY 0.872340 (3198 2650);
PAINT GREEN (3198 2650);
DISPLAY INVISIBLE (3198 2650);
FORCEADD TAP..1
(3200 2900);
FORCEPROP 3 LASTPIN (3150 2900) SIG_NAME M_F_CPU0_SA_DQS_DN<1>
J 0
(3160 2910);
DISPLAY 0.659574 (3160 2910);
PAINT MONO (3160 2910);
DISPLAY INVISIBLE (3160 2910);
FORCEPROP 1 LASTPIN (3150 2900) BN 1
J 0
(3138 2908);
DISPLAY 0.680851 (3138 2908);
PAINT GREEN (3138 2908);
FORCEPROP 2 LAST CDS_LIB standard
J 0
(3200 2900);
DISPLAY INVISIBLE (3200 2900);
FORCEPROP 1 LAST BODY_TYPE PLUMBING
J 0
(3200 2950);
DISPLAY 0.872340 (3200 2950);
PAINT GREEN (3200 2950);
DISPLAY INVISIBLE (3200 2950);
FORCEPROP 1 LAST HDL_TAP TRUE
J 0
(3525 2775);
DISPLAY 0.872340 (3525 2775);
DISPLAY INVISIBLE (3525 2775);
FORCEPROP 1 LAST PATH I144
J 0
(3198 2900);
DISPLAY 0.872340 (3198 2900);
PAINT GREEN (3198 2900);
DISPLAY INVISIBLE (3198 2900);
FORCEADD TAP..1
(3200 2850);
FORCEPROP 3 LASTPIN (3150 2850) SIG_NAME M_F_CPU0_SA_DQS_DN<0>
J 0
(3160 2860);
DISPLAY 0.659574 (3160 2860);
PAINT MONO (3160 2860);
DISPLAY INVISIBLE (3160 2860);
FORCEPROP 1 LASTPIN (3150 2850) BN 0
J 0
(3138 2858);
DISPLAY 0.680851 (3138 2858);
PAINT GREEN (3138 2858);
FORCEPROP 2 LAST CDS_LIB standard
J 0
(3200 2850);
DISPLAY INVISIBLE (3200 2850);
FORCEPROP 1 LAST BODY_TYPE PLUMBING
J 0
(3200 2900);
DISPLAY 0.872340 (3200 2900);
PAINT GREEN (3200 2900);
DISPLAY INVISIBLE (3200 2900);
FORCEPROP 1 LAST HDL_TAP TRUE
J 0
(3525 2725);
DISPLAY 0.872340 (3525 2725);
DISPLAY INVISIBLE (3525 2725);
FORCEPROP 1 LAST PATH I145
J 0
(3198 2850);
DISPLAY 0.872340 (3198 2850);
PAINT GREEN (3198 2850);
DISPLAY INVISIBLE (3198 2850);
FORCEADD TAP..1
(3200 2700);
FORCEPROP 3 LASTPIN (3150 2700) SIG_NAME M_F_CPU0_SB_DQS_DP<9>
J 0
(3160 2710);
DISPLAY 0.659574 (3160 2710);
PAINT MONO (3160 2710);
DISPLAY INVISIBLE (3160 2710);
FORCEPROP 1 LASTPIN (3150 2700) BN 9
J 0
(3138 2708);
DISPLAY 0.680851 (3138 2708);
PAINT GREEN (3138 2708);
FORCEPROP 2 LAST CDS_LIB standard
J 0
(3200 2700);
DISPLAY INVISIBLE (3200 2700);
FORCEPROP 1 LAST BODY_TYPE PLUMBING
J 0
(3200 2750);
DISPLAY 0.872340 (3200 2750);
PAINT GREEN (3200 2750);
DISPLAY INVISIBLE (3200 2750);
FORCEPROP 1 LAST HDL_TAP TRUE
J 0
(3525 2575);
DISPLAY 0.872340 (3525 2575);
DISPLAY INVISIBLE (3525 2575);
FORCEPROP 1 LAST PATH I146
J 0
(3198 2700);
DISPLAY 0.872340 (3198 2700);
PAINT GREEN (3198 2700);
DISPLAY INVISIBLE (3198 2700);
FORCEADD TAP..1
(3200 3000);
FORCEPROP 3 LASTPIN (3150 3000) SIG_NAME M_F_CPU0_SA_DQS_DN<3>
J 0
(3160 3010);
DISPLAY 0.659574 (3160 3010);
PAINT MONO (3160 3010);
DISPLAY INVISIBLE (3160 3010);
FORCEPROP 1 LASTPIN (3150 3000) BN 3
J 0
(3138 3008);
DISPLAY 0.680851 (3138 3008);
PAINT GREEN (3138 3008);
FORCEPROP 2 LAST CDS_LIB standard
J 0
(3200 3000);
DISPLAY INVISIBLE (3200 3000);
FORCEPROP 1 LAST BODY_TYPE PLUMBING
J 0
(3200 3050);
DISPLAY 0.872340 (3200 3050);
PAINT GREEN (3200 3050);
DISPLAY INVISIBLE (3200 3050);
FORCEPROP 1 LAST HDL_TAP TRUE
J 0
(3525 2875);
DISPLAY 0.872340 (3525 2875);
DISPLAY INVISIBLE (3525 2875);
FORCEPROP 1 LAST PATH I147
J 0
(3198 3000);
DISPLAY 0.872340 (3198 3000);
PAINT GREEN (3198 3000);
DISPLAY INVISIBLE (3198 3000);
FORCEADD TAP..1
(3200 2950);
FORCEPROP 3 LASTPIN (3150 2950) SIG_NAME M_F_CPU0_SA_DQS_DN<2>
J 0
(3160 2960);
DISPLAY 0.659574 (3160 2960);
PAINT MONO (3160 2960);
DISPLAY INVISIBLE (3160 2960);
FORCEPROP 1 LASTPIN (3150 2950) BN 2
J 0
(3138 2958);
DISPLAY 0.680851 (3138 2958);
PAINT GREEN (3138 2958);
FORCEPROP 2 LAST CDS_LIB standard
J 0
(3200 2950);
DISPLAY INVISIBLE (3200 2950);
FORCEPROP 1 LAST BODY_TYPE PLUMBING
J 0
(3200 3000);
DISPLAY 0.872340 (3200 3000);
PAINT GREEN (3200 3000);
DISPLAY INVISIBLE (3200 3000);
FORCEPROP 1 LAST HDL_TAP TRUE
J 0
(3525 2825);
DISPLAY 0.872340 (3525 2825);
DISPLAY INVISIBLE (3525 2825);
FORCEPROP 1 LAST PATH I148
J 0
(3198 2950);
DISPLAY 0.872340 (3198 2950);
PAINT GREEN (3198 2950);
DISPLAY INVISIBLE (3198 2950);
FORCEADD TAP..1
(3200 3050);
FORCEPROP 3 LASTPIN (3150 3050) SIG_NAME M_F_CPU0_SA_DQS_DN<4>
J 0
(3160 3060);
DISPLAY 0.659574 (3160 3060);
PAINT MONO (3160 3060);
DISPLAY INVISIBLE (3160 3060);
FORCEPROP 1 LASTPIN (3150 3050) BN 4
J 0
(3138 3058);
DISPLAY 0.680851 (3138 3058);
PAINT GREEN (3138 3058);
FORCEPROP 2 LAST CDS_LIB standard
J 0
(3200 3050);
DISPLAY INVISIBLE (3200 3050);
FORCEPROP 1 LAST BODY_TYPE PLUMBING
J 0
(3200 3100);
DISPLAY 0.872340 (3200 3100);
PAINT GREEN (3200 3100);
DISPLAY INVISIBLE (3200 3100);
FORCEPROP 1 LAST HDL_TAP TRUE
J 0
(3525 2925);
DISPLAY 0.872340 (3525 2925);
DISPLAY INVISIBLE (3525 2925);
FORCEPROP 1 LAST PATH I149
J 0
(3198 3050);
DISPLAY 0.872340 (3198 3050);
PAINT GREEN (3198 3050);
DISPLAY INVISIBLE (3198 3050);
FORCEADD TAP..1
R 2
(-225 200);
FORCEPROP 3 LASTPIN (-175 200) SIG_NAME M_F_CPU0_SB_CB<6>
J 0
(-165 210);
DISPLAY 0.659574 (-165 210);
PAINT MONO (-165 210);
DISPLAY INVISIBLE (-165 210);
FORCEPROP 1 LASTPIN (-175 200) BN 6
J 2
(-163 208);
DISPLAY 0.680851 (-163 208);
PAINT GREEN (-163 208);
FORCEPROP 2 LAST CDS_LIB standard
J 0
(-225 200);
DISPLAY INVISIBLE (-225 200);
FORCEPROP 1 LAST BODY_TYPE PLUMBING
J 2
(-225 250);
DISPLAY 0.872340 (-225 250);
PAINT GREEN (-225 250);
DISPLAY INVISIBLE (-225 250);
FORCEPROP 1 LAST HDL_TAP TRUE
J 2
(-550 75);
DISPLAY 0.872340 (-550 75);
DISPLAY INVISIBLE (-550 75);
FORCEPROP 1 LAST PATH I15
J 2
(-223 200);
DISPLAY 0.872340 (-223 200);
PAINT GREEN (-223 200);
DISPLAY INVISIBLE (-223 200);
FORCEADD TAP..1
(3200 3100);
FORCEPROP 3 LASTPIN (3150 3100) SIG_NAME M_F_CPU0_SA_DQS_DN<5>
J 0
(3160 3110);
DISPLAY 0.659574 (3160 3110);
PAINT MONO (3160 3110);
DISPLAY INVISIBLE (3160 3110);
FORCEPROP 1 LASTPIN (3150 3100) BN 5
J 0
(3138 3108);
DISPLAY 0.680851 (3138 3108);
PAINT GREEN (3138 3108);
FORCEPROP 2 LAST CDS_LIB standard
J 0
(3200 3100);
DISPLAY INVISIBLE (3200 3100);
FORCEPROP 1 LAST BODY_TYPE PLUMBING
J 0
(3200 3150);
DISPLAY 0.872340 (3200 3150);
PAINT GREEN (3200 3150);
DISPLAY INVISIBLE (3200 3150);
FORCEPROP 1 LAST HDL_TAP TRUE
J 0
(3525 2975);
DISPLAY 0.872340 (3525 2975);
DISPLAY INVISIBLE (3525 2975);
FORCEPROP 1 LAST PATH I150
J 0
(3198 3100);
DISPLAY 0.872340 (3198 3100);
PAINT GREEN (3198 3100);
DISPLAY INVISIBLE (3198 3100);
FORCEADD TAP..1
(3200 3150);
FORCEPROP 3 LASTPIN (3150 3150) SIG_NAME M_F_CPU0_SA_DQS_DN<6>
J 0
(3160 3160);
DISPLAY 0.659574 (3160 3160);
PAINT MONO (3160 3160);
DISPLAY INVISIBLE (3160 3160);
FORCEPROP 1 LASTPIN (3150 3150) BN 6
J 0
(3138 3158);
DISPLAY 0.680851 (3138 3158);
PAINT GREEN (3138 3158);
FORCEPROP 2 LAST CDS_LIB standard
J 0
(3200 3150);
DISPLAY INVISIBLE (3200 3150);
FORCEPROP 1 LAST BODY_TYPE PLUMBING
J 0
(3200 3200);
DISPLAY 0.872340 (3200 3200);
PAINT GREEN (3200 3200);
DISPLAY INVISIBLE (3200 3200);
FORCEPROP 1 LAST HDL_TAP TRUE
J 0
(3525 3025);
DISPLAY 0.872340 (3525 3025);
DISPLAY INVISIBLE (3525 3025);
FORCEPROP 1 LAST PATH I151
J 0
(3198 3150);
DISPLAY 0.872340 (3198 3150);
PAINT GREEN (3198 3150);
DISPLAY INVISIBLE (3198 3150);
FORCEADD TAP..1
(3200 3400);
FORCEPROP 3 LASTPIN (3150 3400) SIG_NAME M_F_CPU0_SA_DQS_DP<0>
J 0
(3160 3410);
DISPLAY 0.659574 (3160 3410);
PAINT MONO (3160 3410);
DISPLAY INVISIBLE (3160 3410);
FORCEPROP 1 LASTPIN (3150 3400) BN 0
J 0
(3138 3408);
DISPLAY 0.680851 (3138 3408);
PAINT GREEN (3138 3408);
FORCEPROP 2 LAST CDS_LIB standard
J 0
(3200 3400);
DISPLAY INVISIBLE (3200 3400);
FORCEPROP 1 LAST BODY_TYPE PLUMBING
J 0
(3200 3450);
DISPLAY 0.872340 (3200 3450);
PAINT GREEN (3200 3450);
DISPLAY INVISIBLE (3200 3450);
FORCEPROP 1 LAST HDL_TAP TRUE
J 0
(3525 3275);
DISPLAY 0.872340 (3525 3275);
DISPLAY INVISIBLE (3525 3275);
FORCEPROP 1 LAST PATH I152
J 0
(3198 3400);
DISPLAY 0.872340 (3198 3400);
PAINT GREEN (3198 3400);
DISPLAY INVISIBLE (3198 3400);
FORCEADD TAP..1
(3200 3200);
FORCEPROP 3 LASTPIN (3150 3200) SIG_NAME M_F_CPU0_SA_DQS_DN<7>
J 0
(3160 3210);
DISPLAY 0.659574 (3160 3210);
PAINT MONO (3160 3210);
DISPLAY INVISIBLE (3160 3210);
FORCEPROP 1 LASTPIN (3150 3200) BN 7
J 0
(3138 3208);
DISPLAY 0.680851 (3138 3208);
PAINT GREEN (3138 3208);
FORCEPROP 2 LAST CDS_LIB standard
J 0
(3200 3200);
DISPLAY INVISIBLE (3200 3200);
FORCEPROP 1 LAST BODY_TYPE PLUMBING
J 0
(3200 3250);
DISPLAY 0.872340 (3200 3250);
PAINT GREEN (3200 3250);
DISPLAY INVISIBLE (3200 3250);
FORCEPROP 1 LAST HDL_TAP TRUE
J 0
(3525 3075);
DISPLAY 0.872340 (3525 3075);
DISPLAY INVISIBLE (3525 3075);
FORCEPROP 1 LAST PATH I153
J 0
(3198 3200);
DISPLAY 0.872340 (3198 3200);
PAINT GREEN (3198 3200);
DISPLAY INVISIBLE (3198 3200);
FORCEADD TAP..1
(3200 3250);
FORCEPROP 3 LASTPIN (3150 3250) SIG_NAME M_F_CPU0_SA_DQS_DN<8>
J 0
(3160 3260);
DISPLAY 0.659574 (3160 3260);
PAINT MONO (3160 3260);
DISPLAY INVISIBLE (3160 3260);
FORCEPROP 1 LASTPIN (3150 3250) BN 8
J 0
(3138 3258);
DISPLAY 0.680851 (3138 3258);
PAINT GREEN (3138 3258);
FORCEPROP 2 LAST CDS_LIB standard
J 0
(3200 3250);
DISPLAY INVISIBLE (3200 3250);
FORCEPROP 1 LAST BODY_TYPE PLUMBING
J 0
(3200 3300);
DISPLAY 0.872340 (3200 3300);
PAINT GREEN (3200 3300);
DISPLAY INVISIBLE (3200 3300);
FORCEPROP 1 LAST HDL_TAP TRUE
J 0
(3525 3125);
DISPLAY 0.872340 (3525 3125);
DISPLAY INVISIBLE (3525 3125);
FORCEPROP 1 LAST PATH I154
J 0
(3198 3250);
DISPLAY 0.872340 (3198 3250);
PAINT GREEN (3198 3250);
DISPLAY INVISIBLE (3198 3250);
FORCEADD TAP..1
(3200 3300);
FORCEPROP 3 LASTPIN (3150 3300) SIG_NAME M_F_CPU0_SA_DQS_DN<9>
J 0
(3160 3310);
DISPLAY 0.659574 (3160 3310);
PAINT MONO (3160 3310);
DISPLAY INVISIBLE (3160 3310);
FORCEPROP 1 LASTPIN (3150 3300) BN 9
J 0
(3138 3308);
DISPLAY 0.680851 (3138 3308);
PAINT GREEN (3138 3308);
FORCEPROP 2 LAST CDS_LIB standard
J 0
(3200 3300);
DISPLAY INVISIBLE (3200 3300);
FORCEPROP 1 LAST BODY_TYPE PLUMBING
J 0
(3200 3350);
DISPLAY 0.872340 (3200 3350);
PAINT GREEN (3200 3350);
DISPLAY INVISIBLE (3200 3350);
FORCEPROP 1 LAST HDL_TAP TRUE
J 0
(3525 3175);
DISPLAY 0.872340 (3525 3175);
DISPLAY INVISIBLE (3525 3175);
FORCEPROP 1 LAST PATH I155
J 0
(3198 3300);
DISPLAY 0.872340 (3198 3300);
PAINT GREEN (3198 3300);
DISPLAY INVISIBLE (3198 3300);
FORCEADD TAP..1
(3200 3450);
FORCEPROP 3 LASTPIN (3150 3450) SIG_NAME M_F_CPU0_SA_DQS_DP<1>
J 0
(3160 3460);
DISPLAY 0.659574 (3160 3460);
PAINT MONO (3160 3460);
DISPLAY INVISIBLE (3160 3460);
FORCEPROP 1 LASTPIN (3150 3450) BN 1
J 0
(3138 3458);
DISPLAY 0.680851 (3138 3458);
PAINT GREEN (3138 3458);
FORCEPROP 2 LAST CDS_LIB standard
J 0
(3200 3450);
DISPLAY INVISIBLE (3200 3450);
FORCEPROP 1 LAST BODY_TYPE PLUMBING
J 0
(3200 3500);
DISPLAY 0.872340 (3200 3500);
PAINT GREEN (3200 3500);
DISPLAY INVISIBLE (3200 3500);
FORCEPROP 1 LAST HDL_TAP TRUE
J 0
(3525 3325);
DISPLAY 0.872340 (3525 3325);
DISPLAY INVISIBLE (3525 3325);
FORCEPROP 1 LAST PATH I156
J 0
(3198 3450);
DISPLAY 0.872340 (3198 3450);
PAINT GREEN (3198 3450);
DISPLAY INVISIBLE (3198 3450);
FORCEADD TAP..1
(3200 3500);
FORCEPROP 3 LASTPIN (3150 3500) SIG_NAME M_F_CPU0_SA_DQS_DP<2>
J 0
(3160 3510);
DISPLAY 0.659574 (3160 3510);
PAINT MONO (3160 3510);
DISPLAY INVISIBLE (3160 3510);
FORCEPROP 1 LASTPIN (3150 3500) BN 2
J 0
(3138 3508);
DISPLAY 0.680851 (3138 3508);
PAINT GREEN (3138 3508);
FORCEPROP 2 LAST CDS_LIB standard
J 0
(3200 3500);
DISPLAY INVISIBLE (3200 3500);
FORCEPROP 1 LAST BODY_TYPE PLUMBING
J 0
(3200 3550);
DISPLAY 0.872340 (3200 3550);
PAINT GREEN (3200 3550);
DISPLAY INVISIBLE (3200 3550);
FORCEPROP 1 LAST HDL_TAP TRUE
J 0
(3525 3375);
DISPLAY 0.872340 (3525 3375);
DISPLAY INVISIBLE (3525 3375);
FORCEPROP 1 LAST PATH I157
J 0
(3198 3500);
DISPLAY 0.872340 (3198 3500);
PAINT GREEN (3198 3500);
DISPLAY INVISIBLE (3198 3500);
FORCEADD TAP..1
(3200 3600);
FORCEPROP 3 LASTPIN (3150 3600) SIG_NAME M_F_CPU0_SA_DQS_DP<4>
J 0
(3160 3610);
DISPLAY 0.659574 (3160 3610);
PAINT MONO (3160 3610);
DISPLAY INVISIBLE (3160 3610);
FORCEPROP 1 LASTPIN (3150 3600) BN 4
J 0
(3138 3608);
DISPLAY 0.680851 (3138 3608);
PAINT GREEN (3138 3608);
FORCEPROP 2 LAST CDS_LIB standard
J 0
(3200 3600);
DISPLAY INVISIBLE (3200 3600);
FORCEPROP 1 LAST BODY_TYPE PLUMBING
J 0
(3200 3650);
DISPLAY 0.872340 (3200 3650);
PAINT GREEN (3200 3650);
DISPLAY INVISIBLE (3200 3650);
FORCEPROP 1 LAST HDL_TAP TRUE
J 0
(3525 3475);
DISPLAY 0.872340 (3525 3475);
DISPLAY INVISIBLE (3525 3475);
FORCEPROP 1 LAST PATH I158
J 0
(3198 3600);
DISPLAY 0.872340 (3198 3600);
PAINT GREEN (3198 3600);
DISPLAY INVISIBLE (3198 3600);
FORCEADD TAP..1
(3200 3650);
FORCEPROP 3 LASTPIN (3150 3650) SIG_NAME M_F_CPU0_SA_DQS_DP<5>
J 0
(3160 3660);
DISPLAY 0.659574 (3160 3660);
PAINT MONO (3160 3660);
DISPLAY INVISIBLE (3160 3660);
FORCEPROP 1 LASTPIN (3150 3650) BN 5
J 0
(3138 3658);
DISPLAY 0.680851 (3138 3658);
PAINT GREEN (3138 3658);
FORCEPROP 2 LAST CDS_LIB standard
J 0
(3200 3650);
DISPLAY INVISIBLE (3200 3650);
FORCEPROP 1 LAST BODY_TYPE PLUMBING
J 0
(3200 3700);
DISPLAY 0.872340 (3200 3700);
PAINT GREEN (3200 3700);
DISPLAY INVISIBLE (3200 3700);
FORCEPROP 1 LAST HDL_TAP TRUE
J 0
(3525 3525);
DISPLAY 0.872340 (3525 3525);
DISPLAY INVISIBLE (3525 3525);
FORCEPROP 1 LAST PATH I159
J 0
(3198 3650);
DISPLAY 0.872340 (3198 3650);
PAINT GREEN (3198 3650);
DISPLAY INVISIBLE (3198 3650);
FORCEADD TAP..1
R 2
(-225 150);
FORCEPROP 3 LASTPIN (-175 150) SIG_NAME M_F_CPU0_SB_CB<5>
J 0
(-165 160);
DISPLAY 0.659574 (-165 160);
PAINT MONO (-165 160);
DISPLAY INVISIBLE (-165 160);
FORCEPROP 1 LASTPIN (-175 150) BN 5
J 2
(-163 158);
DISPLAY 0.680851 (-163 158);
PAINT GREEN (-163 158);
FORCEPROP 2 LAST CDS_LIB standard
J 0
(-225 150);
DISPLAY INVISIBLE (-225 150);
FORCEPROP 1 LAST BODY_TYPE PLUMBING
J 2
(-225 200);
DISPLAY 0.872340 (-225 200);
PAINT GREEN (-225 200);
DISPLAY INVISIBLE (-225 200);
FORCEPROP 1 LAST HDL_TAP TRUE
J 2
(-550 25);
DISPLAY 0.872340 (-550 25);
DISPLAY INVISIBLE (-550 25);
FORCEPROP 1 LAST PATH I16
J 2
(-223 150);
DISPLAY 0.872340 (-223 150);
PAINT GREEN (-223 150);
DISPLAY INVISIBLE (-223 150);
FORCEADD TAP..1
(3200 3550);
FORCEPROP 3 LASTPIN (3150 3550) SIG_NAME M_F_CPU0_SA_DQS_DP<3>
J 0
(3160 3560);
DISPLAY 0.659574 (3160 3560);
PAINT MONO (3160 3560);
DISPLAY INVISIBLE (3160 3560);
FORCEPROP 1 LASTPIN (3150 3550) BN 3
J 0
(3138 3558);
DISPLAY 0.680851 (3138 3558);
PAINT GREEN (3138 3558);
FORCEPROP 2 LAST CDS_LIB standard
J 0
(3200 3550);
DISPLAY INVISIBLE (3200 3550);
FORCEPROP 1 LAST BODY_TYPE PLUMBING
J 0
(3200 3600);
DISPLAY 0.872340 (3200 3600);
PAINT GREEN (3200 3600);
DISPLAY INVISIBLE (3200 3600);
FORCEPROP 1 LAST HDL_TAP TRUE
J 0
(3525 3425);
DISPLAY 0.872340 (3525 3425);
DISPLAY INVISIBLE (3525 3425);
FORCEPROP 1 LAST PATH I160
J 0
(3198 3550);
DISPLAY 0.872340 (3198 3550);
PAINT GREEN (3198 3550);
DISPLAY INVISIBLE (3198 3550);
FORCEADD TAP..1
(3200 3700);
FORCEPROP 3 LASTPIN (3150 3700) SIG_NAME M_F_CPU0_SA_DQS_DP<6>
J 0
(3160 3710);
DISPLAY 0.659574 (3160 3710);
PAINT MONO (3160 3710);
DISPLAY INVISIBLE (3160 3710);
FORCEPROP 1 LASTPIN (3150 3700) BN 6
J 0
(3138 3708);
DISPLAY 0.680851 (3138 3708);
PAINT GREEN (3138 3708);
FORCEPROP 2 LAST CDS_LIB standard
J 0
(3200 3700);
DISPLAY INVISIBLE (3200 3700);
FORCEPROP 1 LAST BODY_TYPE PLUMBING
J 0
(3200 3750);
DISPLAY 0.872340 (3200 3750);
PAINT GREEN (3200 3750);
DISPLAY INVISIBLE (3200 3750);
FORCEPROP 1 LAST HDL_TAP TRUE
J 0
(3525 3575);
DISPLAY 0.872340 (3525 3575);
DISPLAY INVISIBLE (3525 3575);
FORCEPROP 1 LAST PATH I161
J 0
(3198 3700);
DISPLAY 0.872340 (3198 3700);
PAINT GREEN (3198 3700);
DISPLAY INVISIBLE (3198 3700);
FORCEADD TAP..1
(3200 3750);
FORCEPROP 3 LASTPIN (3150 3750) SIG_NAME M_F_CPU0_SA_DQS_DP<7>
J 0
(3160 3760);
DISPLAY 0.659574 (3160 3760);
PAINT MONO (3160 3760);
DISPLAY INVISIBLE (3160 3760);
FORCEPROP 1 LASTPIN (3150 3750) BN 7
J 0
(3138 3758);
DISPLAY 0.680851 (3138 3758);
PAINT GREEN (3138 3758);
FORCEPROP 2 LAST CDS_LIB standard
J 0
(3200 3750);
DISPLAY INVISIBLE (3200 3750);
FORCEPROP 1 LAST BODY_TYPE PLUMBING
J 0
(3200 3800);
DISPLAY 0.872340 (3200 3800);
PAINT GREEN (3200 3800);
DISPLAY INVISIBLE (3200 3800);
FORCEPROP 1 LAST HDL_TAP TRUE
J 0
(3525 3625);
DISPLAY 0.872340 (3525 3625);
DISPLAY INVISIBLE (3525 3625);
FORCEPROP 1 LAST PATH I162
J 0
(3198 3750);
DISPLAY 0.872340 (3198 3750);
PAINT GREEN (3198 3750);
DISPLAY INVISIBLE (3198 3750);
FORCEADD TAP..1
(3200 3850);
FORCEPROP 3 LASTPIN (3150 3850) SIG_NAME M_F_CPU0_SA_DQS_DP<9>
J 0
(3160 3860);
DISPLAY 0.659574 (3160 3860);
PAINT MONO (3160 3860);
DISPLAY INVISIBLE (3160 3860);
FORCEPROP 1 LASTPIN (3150 3850) BN 9
J 0
(3138 3858);
DISPLAY 0.680851 (3138 3858);
PAINT GREEN (3138 3858);
FORCEPROP 2 LAST CDS_LIB standard
J 0
(3200 3850);
DISPLAY INVISIBLE (3200 3850);
FORCEPROP 1 LAST BODY_TYPE PLUMBING
J 0
(3200 3900);
DISPLAY 0.872340 (3200 3900);
PAINT GREEN (3200 3900);
DISPLAY INVISIBLE (3200 3900);
FORCEPROP 1 LAST HDL_TAP TRUE
J 0
(3525 3725);
DISPLAY 0.872340 (3525 3725);
DISPLAY INVISIBLE (3525 3725);
FORCEPROP 1 LAST PATH I163
J 0
(3198 3850);
DISPLAY 0.872340 (3198 3850);
PAINT GREEN (3198 3850);
DISPLAY INVISIBLE (3198 3850);
FORCEADD TAP..1
(3200 3800);
FORCEPROP 3 LASTPIN (3150 3800) SIG_NAME M_F_CPU0_SA_DQS_DP<8>
J 0
(3160 3810);
DISPLAY 0.659574 (3160 3810);
PAINT MONO (3160 3810);
DISPLAY INVISIBLE (3160 3810);
FORCEPROP 1 LASTPIN (3150 3800) BN 8
J 0
(3138 3808);
DISPLAY 0.680851 (3138 3808);
PAINT GREEN (3138 3808);
FORCEPROP 2 LAST CDS_LIB standard
J 0
(3200 3800);
DISPLAY INVISIBLE (3200 3800);
FORCEPROP 1 LAST BODY_TYPE PLUMBING
J 0
(3200 3850);
DISPLAY 0.872340 (3200 3850);
PAINT GREEN (3200 3850);
DISPLAY INVISIBLE (3200 3850);
FORCEPROP 1 LAST HDL_TAP TRUE
J 0
(3525 3675);
DISPLAY 0.872340 (3525 3675);
DISPLAY INVISIBLE (3525 3675);
FORCEPROP 1 LAST PATH I164
J 0
(3198 3800);
DISPLAY 0.872340 (3198 3800);
PAINT GREEN (3198 3800);
DISPLAY INVISIBLE (3198 3800);
FORCEADD OFFPAGE..3
(4300 2175);
FORCEPROP 2 LAST $XR1 93 
J 0
(4604 2175);
DISPLAY 0.638298 (4604 2175);
PAINT MONO (4604 2175);
FORCEPROP 2 LAST $XR0 92 
J 0
(4514 2175);
DISPLAY 0.638298 (4514 2175);
PAINT MONO (4514 2175);
FORCEPROP 2 LAST CDS_LIB standard
J 2
(4300 2175);
DISPLAY INVISIBLE (4300 2175);
FORCEPROP 1 LAST OFFPAGE TRUE
J 0
(4625 2050);
DISPLAY 0.872340 (4625 2050);
DISPLAY INVISIBLE (4625 2050);
FORCEPROP 1 LAST COMMENT_BODY TRUE
J 0
(4250 2075);
DISPLAY 0.872340 (4250 2075);
PAINT GREEN (4250 2075);
DISPLAY INVISIBLE (4250 2075);
FORCEPROP 2 LAST PATH I165
J 0
(4500 2250);
DISPLAY 1.021277 (4500 2250);
DISPLAY INVISIBLE (4500 2250);
FORCEADD OFFPAGE..3
(4300 2725);
FORCEPROP 2 LAST $XR1 93 
J 0
(4604 2725);
DISPLAY 0.638298 (4604 2725);
PAINT MONO (4604 2725);
FORCEPROP 2 LAST $XR0 92 
J 0
(4514 2725);
DISPLAY 0.638298 (4514 2725);
PAINT MONO (4514 2725);
FORCEPROP 2 LAST CDS_LIB standard
J 2
(4300 2725);
DISPLAY INVISIBLE (4300 2725);
FORCEPROP 1 LAST OFFPAGE TRUE
J 0
(4625 2600);
DISPLAY 0.872340 (4625 2600);
DISPLAY INVISIBLE (4625 2600);
FORCEPROP 1 LAST COMMENT_BODY TRUE
J 0
(4250 2625);
DISPLAY 0.872340 (4250 2625);
PAINT GREEN (4250 2625);
DISPLAY INVISIBLE (4250 2625);
FORCEPROP 2 LAST PATH I166
J 0
(4500 2800);
DISPLAY 1.021277 (4500 2800);
DISPLAY INVISIBLE (4500 2800);
FORCEADD OFFPAGE..3
(4300 3325);
FORCEPROP 2 LAST $XR1 93 
J 0
(4604 3325);
DISPLAY 0.638298 (4604 3325);
PAINT MONO (4604 3325);
FORCEPROP 2 LAST $XR0 92 
J 0
(4514 3325);
DISPLAY 0.638298 (4514 3325);
PAINT MONO (4514 3325);
FORCEPROP 2 LAST CDS_LIB standard
J 2
(4300 3325);
DISPLAY INVISIBLE (4300 3325);
FORCEPROP 1 LAST OFFPAGE TRUE
J 0
(4625 3200);
DISPLAY 0.872340 (4625 3200);
DISPLAY INVISIBLE (4625 3200);
FORCEPROP 1 LAST COMMENT_BODY TRUE
J 0
(4250 3225);
DISPLAY 0.872340 (4250 3225);
PAINT GREEN (4250 3225);
DISPLAY INVISIBLE (4250 3225);
FORCEPROP 2 LAST PATH I167
J 0
(4500 3400);
DISPLAY 1.021277 (4500 3400);
DISPLAY INVISIBLE (4500 3400);
FORCEADD OFFPAGE..3
(4300 3875);
FORCEPROP 2 LAST $XR1 93 
J 0
(4604 3875);
DISPLAY 0.638298 (4604 3875);
PAINT MONO (4604 3875);
FORCEPROP 2 LAST $XR0 92 
J 0
(4514 3875);
DISPLAY 0.638298 (4514 3875);
PAINT MONO (4514 3875);
FORCEPROP 2 LAST CDS_LIB standard
J 2
(4300 3875);
DISPLAY INVISIBLE (4300 3875);
FORCEPROP 1 LAST OFFPAGE TRUE
J 0
(4625 3750);
DISPLAY 0.872340 (4625 3750);
DISPLAY INVISIBLE (4625 3750);
FORCEPROP 1 LAST COMMENT_BODY TRUE
J 0
(4250 3775);
DISPLAY 0.872340 (4250 3775);
PAINT GREEN (4250 3775);
DISPLAY INVISIBLE (4250 3775);
FORCEPROP 2 LAST PATH I168
J 0
(4500 3950);
DISPLAY 1.021277 (4500 3950);
DISPLAY INVISIBLE (4500 3950);
FORCEADD SOCKET4677_AZIF0045P001C01CS..13
(1500 1750);
FORCEPROP 1 LAST PART_NUMBER DGA^7000023
J 0
(400 4100);
DISPLAY 0.723404 (400 4100);
PAINT GREEN (400 4100);
DISPLAY INVISIBLE (400 4100);
FORCEPROP 2 LAST PART_TYPE SMLF
J 0
(400 4275);
DISPLAY 1.021277 (400 4275);
FORCEPROP 1 LAST MATERIAL IO
J 0
(400 4025);
DISPLAY 0.723404 (400 4025);
PAINT GREEN (400 4025);
FORCEPROP 2 LAST VALUE SOCKET4677_AZIF0045-P001C01CS
J 0
(400 4225);
DISPLAY 1.021277 (400 4225);
FORCEPROP 1 LAST $LOCATION U2
J 0
(400 4175);
DISPLAY 0.723404 (400 4175);
PAINT GREEN (400 4175);
FORCEPROP 0 LASTPIN (2725 -100) $PN DN48
J 0
(2735 -90);
DISPLAY 0.680851 (2735 -90);
PAINT MONO (2735 -90);
FORCEPROP 0 LASTPIN (2725 -50) $PN DP47
J 0
(2735 -40);
DISPLAY 0.680851 (2735 -40);
PAINT MONO (2735 -40);
FORCEPROP 0 LASTPIN (2725 -350) $PN CW48
J 0
(2735 -340);
DISPLAY 0.680851 (2735 -340);
PAINT MONO (2735 -340);
FORCEPROP 0 LASTPIN (2725 -250) $PN DL48
J 0
(2735 -240);
DISPLAY 0.680851 (2735 -240);
PAINT MONO (2735 -240);
FORCEPROP 0 LASTPIN (2725 -200) $PN DK47
J 0
(2735 -190);
DISPLAY 0.680851 (2735 -190);
PAINT MONO (2735 -190);
FORCEPROP 0 LASTPIN (275 -350) $PN DY49
J 2
(265 -340);
DISPLAY 0.680851 (265 -340);
PAINT MONO (265 -340);
FORCEPROP 0 LASTPIN (275 -300) $PN DV49
J 2
(265 -290);
DISPLAY 0.680851 (265 -290);
PAINT MONO (265 -290);
FORCEPROP 0 LASTPIN (275 -250) $PN EB49
J 2
(265 -240);
DISPLAY 0.680851 (265 -240);
PAINT MONO (265 -240);
FORCEPROP 0 LASTPIN (275 -200) $PN DT49
J 2
(265 -190);
DISPLAY 0.680851 (265 -190);
PAINT MONO (265 -190);
FORCEPROP 0 LASTPIN (2725 1250) $PN EC52
J 0
(2735 1260);
DISPLAY 0.680851 (2735 1260);
PAINT MONO (2735 1260);
FORCEPROP 0 LASTPIN (2725 1300) $PN EJ52
J 0
(2735 1310);
DISPLAY 0.680851 (2735 1310);
PAINT MONO (2735 1310);
FORCEPROP 0 LASTPIN (2725 1350) $PN ED51
J 0
(2735 1360);
DISPLAY 0.680851 (2735 1360);
PAINT MONO (2735 1360);
FORCEPROP 0 LASTPIN (2725 1400) $PN EH51
J 0
(2735 1410);
DISPLAY 0.680851 (2735 1410);
PAINT MONO (2735 1410);
FORCEPROP 0 LASTPIN (2725 1450) $PN EE50
J 0
(2735 1460);
DISPLAY 0.680851 (2735 1460);
PAINT MONO (2735 1460);
FORCEPROP 0 LASTPIN (2725 1500) $PN EG50
J 0
(2735 1510);
DISPLAY 0.680851 (2735 1510);
PAINT MONO (2735 1510);
FORCEPROP 0 LASTPIN (2725 1550) $PN DY51
J 0
(2735 1560);
DISPLAY 0.680851 (2735 1560);
PAINT MONO (2735 1560);
FORCEPROP 0 LASTPIN (275 2300) $PN EB77
J 2
(265 2310);
DISPLAY 0.680851 (265 2310);
PAINT MONO (265 2310);
FORCEPROP 0 LASTPIN (275 2350) $PN EH77
J 2
(265 2360);
DISPLAY 0.680851 (265 2360);
PAINT MONO (265 2360);
FORCEPROP 0 LASTPIN (275 2400) $PN ED77
J 2
(265 2410);
DISPLAY 0.680851 (265 2410);
PAINT MONO (265 2410);
FORCEPROP 0 LASTPIN (275 2450) $PN EG78
J 2
(265 2460);
DISPLAY 0.680851 (265 2460);
PAINT MONO (265 2460);
FORCEPROP 0 LASTPIN (275 2500) $PN ED75
J 2
(265 2510);
DISPLAY 0.680851 (265 2510);
PAINT MONO (265 2510);
FORCEPROP 0 LASTPIN (275 2550) $PN EE74
J 2
(265 2560);
DISPLAY 0.680851 (265 2560);
PAINT MONO (265 2560);
FORCEPROP 0 LASTPIN (275 2600) $PN EH75
J 2
(265 2610);
DISPLAY 0.680851 (265 2610);
PAINT MONO (265 2610);
FORCEPROP 0 LASTPIN (275 2650) $PN EG74
J 2
(265 2660);
DISPLAY 0.680851 (265 2660);
PAINT MONO (265 2660);
FORCEPROP 0 LASTPIN (275 2700) $PN DV69
J 2
(265 2710);
DISPLAY 0.680851 (265 2710);
PAINT MONO (265 2710);
FORCEPROP 0 LASTPIN (275 2750) $PN DU68
J 2
(265 2760);
DISPLAY 0.680851 (265 2760);
PAINT MONO (265 2760);
FORCEPROP 0 LASTPIN (275 2800) $PN DY69
J 2
(265 2810);
DISPLAY 0.680851 (265 2810);
PAINT MONO (265 2810);
FORCEPROP 0 LASTPIN (275 2850) $PN EA68
J 2
(265 2860);
DISPLAY 0.680851 (265 2860);
PAINT MONO (265 2860);
FORCEPROP 0 LASTPIN (275 2900) $PN DU66
J 2
(265 2910);
DISPLAY 0.680851 (265 2910);
PAINT MONO (265 2910);
FORCEPROP 0 LASTPIN (275 2950) $PN DV65
J 2
(265 2960);
DISPLAY 0.680851 (265 2960);
PAINT MONO (265 2960);
FORCEPROP 0 LASTPIN (275 3000) $PN EA66
J 2
(265 3010);
DISPLAY 0.680851 (265 3010);
PAINT MONO (265 3010);
FORCEPROP 0 LASTPIN (275 3050) $PN DY65
J 2
(265 3060);
DISPLAY 0.680851 (265 3060);
PAINT MONO (265 3060);
FORCEPROP 0 LASTPIN (275 3100) $PN EE66
J 2
(265 3110);
DISPLAY 0.680851 (265 3110);
PAINT MONO (265 3110);
FORCEPROP 0 LASTPIN (275 3150) $PN ED65
J 2
(265 3160);
DISPLAY 0.680851 (265 3160);
PAINT MONO (265 3160);
FORCEPROP 0 LASTPIN (275 3200) $PN EG66
J 2
(265 3210);
DISPLAY 0.680851 (265 3210);
PAINT MONO (265 3210);
FORCEPROP 0 LASTPIN (275 3250) $PN EH65
J 2
(265 3260);
DISPLAY 0.680851 (265 3260);
PAINT MONO (265 3260);
FORCEPROP 0 LASTPIN (275 3300) $PN ED63
J 2
(265 3310);
DISPLAY 0.680851 (265 3310);
PAINT MONO (265 3310);
FORCEPROP 0 LASTPIN (275 3350) $PN EE62
J 2
(265 3360);
DISPLAY 0.680851 (265 3360);
PAINT MONO (265 3360);
FORCEPROP 0 LASTPIN (275 3400) $PN EH63
J 2
(265 3410);
DISPLAY 0.680851 (265 3410);
PAINT MONO (265 3410);
FORCEPROP 0 LASTPIN (275 3450) $PN EG62
J 2
(265 3460);
DISPLAY 0.680851 (265 3460);
PAINT MONO (265 3460);
FORCEPROP 0 LASTPIN (275 3500) $PN DV57
J 2
(265 3510);
DISPLAY 0.680851 (265 3510);
PAINT MONO (265 3510);
FORCEPROP 0 LASTPIN (275 3550) $PN DU56
J 2
(265 3560);
DISPLAY 0.680851 (265 3560);
PAINT MONO (265 3560);
FORCEPROP 0 LASTPIN (275 3600) $PN DY57
J 2
(265 3610);
DISPLAY 0.680851 (265 3610);
PAINT MONO (265 3610);
FORCEPROP 0 LASTPIN (275 3650) $PN EA56
J 2
(265 3660);
DISPLAY 0.680851 (265 3660);
PAINT MONO (265 3660);
FORCEPROP 0 LASTPIN (275 3700) $PN DU54
J 2
(265 3710);
DISPLAY 0.680851 (265 3710);
PAINT MONO (265 3710);
FORCEPROP 0 LASTPIN (275 3750) $PN DV53
J 2
(265 3760);
DISPLAY 0.680851 (265 3760);
PAINT MONO (265 3760);
FORCEPROP 0 LASTPIN (275 3800) $PN EA54
J 2
(265 3810);
DISPLAY 0.680851 (265 3810);
PAINT MONO (265 3810);
FORCEPROP 0 LASTPIN (275 3850) $PN DY53
J 2
(265 3860);
DISPLAY 0.680851 (265 3860);
PAINT MONO (265 3860);
FORCEPROP 0 LASTPIN (2725 2850) $PN EE76
J 0
(2735 2860);
DISPLAY 0.680851 (2735 2860);
PAINT MONO (2735 2860);
FORCEPROP 0 LASTPIN (2725 2900) $PN DT67
J 0
(2735 2910);
DISPLAY 0.680851 (2735 2910);
PAINT MONO (2735 2910);
FORCEPROP 0 LASTPIN (2725 2950) $PN EC64
J 0
(2735 2960);
DISPLAY 0.680851 (2735 2960);
PAINT MONO (2735 2960);
FORCEPROP 0 LASTPIN (2725 3000) $PN DV55
J 0
(2735 3010);
DISPLAY 0.680851 (2735 3010);
PAINT MONO (2735 3010);
FORCEPROP 0 LASTPIN (2725 3050) $PN EE58
J 0
(2735 3060);
DISPLAY 0.680851 (2735 3060);
PAINT MONO (2735 3060);
FORCEPROP 0 LASTPIN (2725 3100) $PN EJ76
J 0
(2735 3110);
DISPLAY 0.680851 (2735 3110);
PAINT MONO (2735 3110);
FORCEPROP 0 LASTPIN (2725 3150) $PN EB67
J 0
(2735 3160);
DISPLAY 0.680851 (2735 3160);
PAINT MONO (2735 3160);
FORCEPROP 0 LASTPIN (2725 3200) $PN EJ64
J 0
(2735 3210);
DISPLAY 0.680851 (2735 3210);
PAINT MONO (2735 3210);
FORCEPROP 0 LASTPIN (2725 3250) $PN EB55
J 0
(2735 3260);
DISPLAY 0.680851 (2735 3260);
PAINT MONO (2735 3260);
FORCEPROP 0 LASTPIN (2725 3300) $PN EJ58
J 0
(2735 3310);
DISPLAY 0.680851 (2735 3310);
PAINT MONO (2735 3310);
FORCEPROP 0 LASTPIN (2725 3400) $PN EC76
J 0
(2735 3410);
DISPLAY 0.680851 (2735 3410);
PAINT MONO (2735 3410);
FORCEPROP 0 LASTPIN (2725 3450) $PN DV67
J 0
(2735 3460);
DISPLAY 0.680851 (2735 3460);
PAINT MONO (2735 3460);
FORCEPROP 0 LASTPIN (2725 3500) $PN EE64
J 0
(2735 3510);
DISPLAY 0.680851 (2735 3510);
PAINT MONO (2735 3510);
FORCEPROP 0 LASTPIN (2725 3550) $PN DT55
J 0
(2735 3560);
DISPLAY 0.680851 (2735 3560);
PAINT MONO (2735 3560);
FORCEPROP 0 LASTPIN (2725 3600) $PN EC58
J 0
(2735 3610);
DISPLAY 0.680851 (2735 3610);
PAINT MONO (2735 3610);
FORCEPROP 0 LASTPIN (2725 3650) $PN EG76
J 0
(2735 3660);
DISPLAY 0.680851 (2735 3660);
PAINT MONO (2735 3660);
FORCEPROP 0 LASTPIN (2725 3700) $PN DY67
J 0
(2735 3710);
DISPLAY 0.680851 (2735 3710);
PAINT MONO (2735 3710);
FORCEPROP 0 LASTPIN (2725 3750) $PN EG64
J 0
(2735 3760);
DISPLAY 0.680851 (2735 3760);
PAINT MONO (2735 3760);
FORCEPROP 0 LASTPIN (2725 3800) $PN DY55
J 0
(2735 3810);
DISPLAY 0.680851 (2735 3810);
PAINT MONO (2735 3810);
FORCEPROP 0 LASTPIN (2725 3850) $PN EG58
J 0
(2735 3860);
DISPLAY 0.680851 (2735 3860);
PAINT MONO (2735 3860);
FORCEPROP 0 LASTPIN (275 1900) $PN EE60
J 2
(265 1910);
DISPLAY 0.680851 (265 1910);
PAINT MONO (265 1910);
FORCEPROP 0 LASTPIN (275 1950) $PN ED59
J 2
(265 1960);
DISPLAY 0.680851 (265 1960);
PAINT MONO (265 1960);
FORCEPROP 0 LASTPIN (275 2000) $PN EG60
J 2
(265 2010);
DISPLAY 0.680851 (265 2010);
PAINT MONO (265 2010);
FORCEPROP 0 LASTPIN (275 2050) $PN EH59
J 2
(265 2060);
DISPLAY 0.680851 (265 2060);
PAINT MONO (265 2060);
FORCEPROP 0 LASTPIN (275 2100) $PN ED57
J 2
(265 2110);
DISPLAY 0.680851 (265 2110);
PAINT MONO (265 2110);
FORCEPROP 0 LASTPIN (275 2150) $PN EE56
J 2
(265 2160);
DISPLAY 0.680851 (265 2160);
PAINT MONO (265 2160);
FORCEPROP 0 LASTPIN (275 2200) $PN EH57
J 2
(265 2210);
DISPLAY 0.680851 (265 2210);
PAINT MONO (265 2210);
FORCEPROP 0 LASTPIN (275 2250) $PN EG56
J 2
(265 2260);
DISPLAY 0.680851 (265 2260);
PAINT MONO (265 2260);
FORCEPROP 0 LASTPIN (2725 1200) $PN EA50
J 0
(2735 1210);
DISPLAY 0.680851 (2735 1210);
PAINT MONO (2735 1210);
FORCEPROP 0 LASTPIN (2725 750) $PN DV51
J 0
(2735 760);
DISPLAY 0.680851 (2735 760);
PAINT MONO (2735 760);
FORCEPROP 0 LASTPIN (2725 800) $PN DU50
J 0
(2735 810);
DISPLAY 0.680851 (2735 810);
PAINT MONO (2735 810);
FORCEPROP 0 LASTPIN (2725 850) $PN EE41
J 0
(2735 860);
DISPLAY 0.680851 (2735 860);
PAINT MONO (2735 860);
FORCEPROP 0 LASTPIN (2725 900) $PN EG41
J 0
(2735 910);
DISPLAY 0.680851 (2735 910);
PAINT MONO (2735 910);
FORCEPROP 0 LASTPIN (2725 950) $PN ED40
J 0
(2735 960);
DISPLAY 0.680851 (2735 960);
PAINT MONO (2735 960);
FORCEPROP 0 LASTPIN (2725 1000) $PN EH40
J 0
(2735 1010);
DISPLAY 0.680851 (2735 1010);
PAINT MONO (2735 1010);
FORCEPROP 0 LASTPIN (2725 1050) $PN EC39
J 0
(2735 1060);
DISPLAY 0.680851 (2735 1060);
PAINT MONO (2735 1060);
FORCEPROP 0 LASTPIN (275 300) $PN DV32
J 2
(265 310);
DISPLAY 0.680851 (265 310);
PAINT MONO (265 310);
FORCEPROP 0 LASTPIN (275 350) $PN DU31
J 2
(265 360);
DISPLAY 0.680851 (265 360);
PAINT MONO (265 360);
FORCEPROP 0 LASTPIN (275 400) $PN DY32
J 2
(265 410);
DISPLAY 0.680851 (265 410);
PAINT MONO (265 410);
FORCEPROP 0 LASTPIN (275 450) $PN EA31
J 2
(265 460);
DISPLAY 0.680851 (265 460);
PAINT MONO (265 460);
FORCEPROP 0 LASTPIN (275 500) $PN DU29
J 2
(265 510);
DISPLAY 0.680851 (265 510);
PAINT MONO (265 510);
FORCEPROP 0 LASTPIN (275 550) $PN DV28
J 2
(265 560);
DISPLAY 0.680851 (265 560);
PAINT MONO (265 560);
FORCEPROP 0 LASTPIN (275 600) $PN EA29
J 2
(265 610);
DISPLAY 0.680851 (265 610);
PAINT MONO (265 610);
FORCEPROP 0 LASTPIN (275 650) $PN DY28
J 2
(265 660);
DISPLAY 0.680851 (265 660);
PAINT MONO (265 660);
FORCEPROP 0 LASTPIN (275 700) $PN EE23
J 2
(265 710);
DISPLAY 0.680851 (265 710);
PAINT MONO (265 710);
FORCEPROP 0 LASTPIN (275 750) $PN ED22
J 2
(265 760);
DISPLAY 0.680851 (265 760);
PAINT MONO (265 760);
FORCEPROP 0 LASTPIN (275 800) $PN EG23
J 2
(265 810);
DISPLAY 0.680851 (265 810);
PAINT MONO (265 810);
FORCEPROP 0 LASTPIN (275 850) $PN EH22
J 2
(265 860);
DISPLAY 0.680851 (265 860);
PAINT MONO (265 860);
FORCEPROP 0 LASTPIN (275 900) $PN ED20
J 2
(265 910);
DISPLAY 0.680851 (265 910);
PAINT MONO (265 910);
FORCEPROP 0 LASTPIN (275 950) $PN EE19
J 2
(265 960);
DISPLAY 0.680851 (265 960);
PAINT MONO (265 960);
FORCEPROP 0 LASTPIN (275 1000) $PN EH20
J 2
(265 1010);
DISPLAY 0.680851 (265 1010);
PAINT MONO (265 1010);
FORCEPROP 0 LASTPIN (275 1050) $PN EG19
J 2
(265 1060);
DISPLAY 0.680851 (265 1060);
PAINT MONO (265 1060);
FORCEPROP 0 LASTPIN (275 1100) $PN EM14
J 2
(265 1110);
DISPLAY 0.680851 (265 1110);
PAINT MONO (265 1110);
FORCEPROP 0 LASTPIN (275 1150) $PN EL13
J 2
(265 1160);
DISPLAY 0.680851 (265 1160);
PAINT MONO (265 1160);
FORCEPROP 0 LASTPIN (275 1200) $PN EP14
J 2
(265 1210);
DISPLAY 0.680851 (265 1210);
PAINT MONO (265 1210);
FORCEPROP 0 LASTPIN (275 1250) $PN ER13
J 2
(265 1260);
DISPLAY 0.680851 (265 1260);
PAINT MONO (265 1260);
FORCEPROP 0 LASTPIN (275 1300) $PN EL11
J 2
(265 1310);
DISPLAY 0.680851 (265 1310);
PAINT MONO (265 1310);
FORCEPROP 0 LASTPIN (275 1350) $PN EM10
J 2
(265 1360);
DISPLAY 0.680851 (265 1360);
PAINT MONO (265 1360);
FORCEPROP 0 LASTPIN (275 1400) $PN ER11
J 2
(265 1410);
DISPLAY 0.680851 (265 1410);
PAINT MONO (265 1410);
FORCEPROP 0 LASTPIN (275 1450) $PN EP10
J 2
(265 1460);
DISPLAY 0.680851 (265 1460);
PAINT MONO (265 1460);
FORCEPROP 0 LASTPIN (275 1500) $PN DV20
J 2
(265 1510);
DISPLAY 0.680851 (265 1510);
PAINT MONO (265 1510);
FORCEPROP 0 LASTPIN (275 1550) $PN DU19
J 2
(265 1560);
DISPLAY 0.680851 (265 1560);
PAINT MONO (265 1560);
FORCEPROP 0 LASTPIN (275 1600) $PN DY20
J 2
(265 1610);
DISPLAY 0.680851 (265 1610);
PAINT MONO (265 1610);
FORCEPROP 0 LASTPIN (275 1650) $PN EA19
J 2
(265 1660);
DISPLAY 0.680851 (265 1660);
PAINT MONO (265 1660);
FORCEPROP 0 LASTPIN (275 1700) $PN EA17
J 2
(265 1710);
DISPLAY 0.680851 (265 1710);
PAINT MONO (265 1710);
FORCEPROP 0 LASTPIN (275 1750) $PN DU17
J 2
(265 1760);
DISPLAY 0.680851 (265 1760);
PAINT MONO (265 1760);
FORCEPROP 0 LASTPIN (275 1800) $PN EC17
J 2
(265 1810);
DISPLAY 0.680851 (265 1810);
PAINT MONO (265 1810);
FORCEPROP 0 LASTPIN (275 1850) $PN DR17
J 2
(265 1860);
DISPLAY 0.680851 (265 1860);
PAINT MONO (265 1860);
FORCEPROP 0 LASTPIN (2725 1700) $PN DV30
J 0
(2735 1710);
DISPLAY 0.680851 (2735 1710);
PAINT MONO (2735 1710);
FORCEPROP 0 LASTPIN (2725 1750) $PN EE21
J 0
(2735 1760);
DISPLAY 0.680851 (2735 1760);
PAINT MONO (2735 1760);
FORCEPROP 0 LASTPIN (2725 1800) $PN EM12
J 0
(2735 1810);
DISPLAY 0.680851 (2735 1810);
PAINT MONO (2735 1810);
FORCEPROP 0 LASTPIN (2725 1850) $PN DT18
J 0
(2735 1860);
DISPLAY 0.680851 (2735 1860);
PAINT MONO (2735 1860);
FORCEPROP 0 LASTPIN (2725 1900) $PN EJ33
J 0
(2735 1910);
DISPLAY 0.680851 (2735 1910);
PAINT MONO (2735 1910);
FORCEPROP 0 LASTPIN (2725 1950) $PN EB30
J 0
(2735 1960);
DISPLAY 0.680851 (2735 1960);
PAINT MONO (2735 1960);
FORCEPROP 0 LASTPIN (2725 2000) $PN EJ21
J 0
(2735 2010);
DISPLAY 0.680851 (2735 2010);
PAINT MONO (2735 2010);
FORCEPROP 0 LASTPIN (2725 2050) $PN ET12
J 0
(2735 2060);
DISPLAY 0.680851 (2735 2060);
PAINT MONO (2735 2060);
FORCEPROP 0 LASTPIN (2725 2100) $PN DY18
J 0
(2735 2110);
DISPLAY 0.680851 (2735 2110);
PAINT MONO (2735 2110);
FORCEPROP 0 LASTPIN (2725 2150) $PN EE33
J 0
(2735 2160);
DISPLAY 0.680851 (2735 2160);
PAINT MONO (2735 2160);
FORCEPROP 0 LASTPIN (2725 2250) $PN DT30
J 0
(2735 2260);
DISPLAY 0.680851 (2735 2260);
PAINT MONO (2735 2260);
FORCEPROP 0 LASTPIN (2725 2300) $PN EC21
J 0
(2735 2310);
DISPLAY 0.680851 (2735 2310);
PAINT MONO (2735 2310);
FORCEPROP 0 LASTPIN (2725 2350) $PN EK12
J 0
(2735 2360);
DISPLAY 0.680851 (2735 2360);
PAINT MONO (2735 2360);
FORCEPROP 0 LASTPIN (2725 2400) $PN DV18
J 0
(2735 2410);
DISPLAY 0.680851 (2735 2410);
PAINT MONO (2735 2410);
FORCEPROP 0 LASTPIN (2725 2450) $PN EG33
J 0
(2735 2460);
DISPLAY 0.680851 (2735 2460);
PAINT MONO (2735 2460);
FORCEPROP 0 LASTPIN (2725 2500) $PN DY30
J 0
(2735 2510);
DISPLAY 0.680851 (2735 2510);
PAINT MONO (2735 2510);
FORCEPROP 0 LASTPIN (2725 2550) $PN EG21
J 0
(2735 2560);
DISPLAY 0.680851 (2735 2560);
PAINT MONO (2735 2560);
FORCEPROP 0 LASTPIN (2725 2600) $PN EP12
J 0
(2735 2610);
DISPLAY 0.680851 (2735 2610);
PAINT MONO (2735 2610);
FORCEPROP 0 LASTPIN (2725 2650) $PN EB18
J 0
(2735 2660);
DISPLAY 0.680851 (2735 2660);
PAINT MONO (2735 2660);
FORCEPROP 0 LASTPIN (2725 2700) $PN EC33
J 0
(2735 2710);
DISPLAY 0.680851 (2735 2710);
PAINT MONO (2735 2710);
FORCEPROP 0 LASTPIN (275 -100) $PN ED32
J 2
(265 -90);
DISPLAY 0.680851 (265 -90);
PAINT MONO (265 -90);
FORCEPROP 0 LASTPIN (275 -50) $PN EE31
J 2
(265 -40);
DISPLAY 0.680851 (265 -40);
PAINT MONO (265 -40);
FORCEPROP 0 LASTPIN (275 0) $PN EH32
J 2
(265 10);
DISPLAY 0.680851 (265 10);
PAINT MONO (265 10);
FORCEPROP 0 LASTPIN (275 50) $PN EG31
J 2
(265 60);
DISPLAY 0.680851 (265 60);
PAINT MONO (265 60);
FORCEPROP 0 LASTPIN (275 100) $PN EE35
J 2
(265 110);
DISPLAY 0.680851 (265 110);
PAINT MONO (265 110);
FORCEPROP 0 LASTPIN (275 150) $PN ED34
J 2
(265 160);
DISPLAY 0.680851 (265 160);
PAINT MONO (265 160);
FORCEPROP 0 LASTPIN (275 200) $PN EG35
J 2
(265 210);
DISPLAY 0.680851 (265 210);
PAINT MONO (265 210);
FORCEPROP 0 LASTPIN (275 250) $PN EH34
J 2
(265 260);
DISPLAY 0.680851 (265 260);
PAINT MONO (265 260);
FORCEPROP 0 LASTPIN (2725 700) $PN EJ39
J 0
(2735 710);
DISPLAY 0.680851 (2735 710);
PAINT MONO (2735 710);
FORCEPROP 0 LASTPIN (2725 400) $PN EG54
J 0
(2735 410);
DISPLAY 0.680851 (2735 410);
PAINT MONO (2735 410);
FORCEPROP 0 LASTPIN (2725 450) $PN EH53
J 0
(2735 460);
DISPLAY 0.680851 (2735 460);
PAINT MONO (2735 460);
FORCEPROP 0 LASTPIN (2725 500) $PN EE54
J 0
(2735 510);
DISPLAY 0.680851 (2735 510);
PAINT MONO (2735 510);
FORCEPROP 0 LASTPIN (2725 550) $PN ED53
J 0
(2735 560);
DISPLAY 0.680851 (2735 560);
PAINT MONO (2735 560);
FORCEPROP 0 LASTPIN (2725 100) $PN EH38
J 0
(2735 110);
DISPLAY 0.680851 (2735 110);
PAINT MONO (2735 110);
FORCEPROP 0 LASTPIN (2725 150) $PN EG37
J 0
(2735 160);
DISPLAY 0.680851 (2735 160);
PAINT MONO (2735 160);
FORCEPROP 0 LASTPIN (2725 200) $PN ED38
J 0
(2735 210);
DISPLAY 0.680851 (2735 210);
PAINT MONO (2735 210);
FORCEPROP 0 LASTPIN (2725 250) $PN EE37
J 0
(2735 260);
DISPLAY 0.680851 (2735 260);
PAINT MONO (2735 260);
FORCEPROP 2 LAST CDS_LIB pure_quanta
J 0
(1500 1750);
DISPLAY INVISIBLE (1500 1750);
FORCEPROP 1 LAST NEEDS_NO_SIZE TRUE
J 0
(1500 1750);
DISPLAY 0.723404 (1500 1750);
PAINT GREEN (1500 1750);
DISPLAY INVISIBLE (1500 1750);
FORCEPROP 1 LAST CDS_LMAN_SYM_OUTLINE -1100,2250,1050,-2250
J 0
(1500 1750);
DISPLAY 0.468085 (1500 1750);
PAINT GREEN (1500 1750);
DISPLAY INVISIBLE (1500 1750);
FORCEPROP 2 LAST CDS_LOCATION U2
J 0
(400 4325);
DISPLAY 1.021277 (400 4325);
DISPLAY INVISIBLE (400 4325);
FORCEPROP 0 LAST $SEC 13
J 0
(400 4325);
DISPLAY 0.680851 (400 4325);
PAINT MONO (400 4325);
DISPLAY INVISIBLE (400 4325);
FORCEPROP 2 LAST CDS_SEC 13
J 0
(400 4325);
DISPLAY 1.021277 (400 4325);
DISPLAY INVISIBLE (400 4325);
FORCEPROP 1 LAST PATH I169
J 0
(1500 1750);
DISPLAY 0.723404 (1500 1750);
PAINT GREEN (1500 1750);
DISPLAY INVISIBLE (1500 1750);
FORCEADD TAP..1
R 2
(-225 300);
FORCEPROP 3 LASTPIN (-175 300) SIG_NAME M_F_CPU0_SB_DQ<0>
J 0
(-165 310);
DISPLAY 0.659574 (-165 310);
PAINT MONO (-165 310);
DISPLAY INVISIBLE (-165 310);
FORCEPROP 1 LASTPIN (-175 300) BN 0
J 2
(-163 308);
DISPLAY 0.680851 (-163 308);
PAINT GREEN (-163 308);
FORCEPROP 2 LAST CDS_LIB standard
J 0
(-225 300);
DISPLAY INVISIBLE (-225 300);
FORCEPROP 1 LAST BODY_TYPE PLUMBING
J 2
(-225 350);
DISPLAY 0.872340 (-225 350);
PAINT GREEN (-225 350);
DISPLAY INVISIBLE (-225 350);
FORCEPROP 1 LAST HDL_TAP TRUE
J 2
(-550 175);
DISPLAY 0.872340 (-550 175);
DISPLAY INVISIBLE (-550 175);
FORCEPROP 1 LAST PATH I17
J 2
(-223 300);
DISPLAY 0.872340 (-223 300);
PAINT GREEN (-223 300);
DISPLAY INVISIBLE (-223 300);
FORCEADD TAP..1
R 2
(-225 250);
FORCEPROP 3 LASTPIN (-175 250) SIG_NAME M_F_CPU0_SB_CB<7>
J 0
(-165 260);
DISPLAY 0.659574 (-165 260);
PAINT MONO (-165 260);
DISPLAY INVISIBLE (-165 260);
FORCEPROP 1 LASTPIN (-175 250) BN 7
J 2
(-163 258);
DISPLAY 0.680851 (-163 258);
PAINT GREEN (-163 258);
FORCEPROP 2 LAST CDS_LIB standard
J 0
(-225 250);
DISPLAY INVISIBLE (-225 250);
FORCEPROP 1 LAST BODY_TYPE PLUMBING
J 2
(-225 300);
DISPLAY 0.872340 (-225 300);
PAINT GREEN (-225 300);
DISPLAY INVISIBLE (-225 300);
FORCEPROP 1 LAST HDL_TAP TRUE
J 2
(-550 125);
DISPLAY 0.872340 (-550 125);
DISPLAY INVISIBLE (-550 125);
FORCEPROP 1 LAST PATH I18
J 2
(-223 250);
DISPLAY 0.872340 (-223 250);
PAINT GREEN (-223 250);
DISPLAY INVISIBLE (-223 250);
FORCEADD TAP..1
R 2
(-225 350);
FORCEPROP 3 LASTPIN (-175 350) SIG_NAME M_F_CPU0_SB_DQ<1>
J 0
(-165 360);
DISPLAY 0.659574 (-165 360);
PAINT MONO (-165 360);
DISPLAY INVISIBLE (-165 360);
FORCEPROP 1 LASTPIN (-175 350) BN 1
J 2
(-163 358);
DISPLAY 0.680851 (-163 358);
PAINT GREEN (-163 358);
FORCEPROP 2 LAST CDS_LIB standard
J 0
(-225 350);
DISPLAY INVISIBLE (-225 350);
FORCEPROP 1 LAST BODY_TYPE PLUMBING
J 2
(-225 400);
DISPLAY 0.872340 (-225 400);
PAINT GREEN (-225 400);
DISPLAY INVISIBLE (-225 400);
FORCEPROP 1 LAST HDL_TAP TRUE
J 2
(-550 225);
DISPLAY 0.872340 (-550 225);
DISPLAY INVISIBLE (-550 225);
FORCEPROP 1 LAST PATH I19
J 2
(-223 350);
DISPLAY 0.872340 (-223 350);
PAINT GREEN (-223 350);
DISPLAY INVISIBLE (-223 350);
FORCEADD OFFPAGE..2
R 2
(-1250 -175);
FORCEPROP 2 LAST $XR1 93 
J 0
(-1594 -175);
DISPLAY 0.638298 (-1594 -175);
PAINT MONO (-1594 -175);
FORCEPROP 2 LAST $XR0 92 
J 0
(-1504 -175);
DISPLAY 0.638298 (-1504 -175);
PAINT MONO (-1504 -175);
FORCEPROP 2 LAST CDS_LIB standard
J 0
(-1250 -175);
PAINT MONO (-1250 -175);
DISPLAY INVISIBLE (-1250 -175);
FORCEPROP 1 LAST OFFPAGE TRUE
J 2
(-1575 -300);
DISPLAY 0.872340 (-1575 -300);
DISPLAY INVISIBLE (-1575 -300);
FORCEPROP 1 LAST COMMENT_BODY TRUE
J 2
(-1205 -270);
DISPLAY 0.872340 (-1205 -270);
PAINT GREEN (-1205 -270);
DISPLAY INVISIBLE (-1205 -270);
FORCEPROP 2 LAST PATH I2
J 0
(-1200 -100);
DISPLAY 1.021277 (-1200 -100);
DISPLAY INVISIBLE (-1200 -100);
FORCEADD TAP..1
R 2
(-225 450);
FORCEPROP 3 LASTPIN (-175 450) SIG_NAME M_F_CPU0_SB_DQ<3>
J 0
(-165 460);
DISPLAY 0.659574 (-165 460);
PAINT MONO (-165 460);
DISPLAY INVISIBLE (-165 460);
FORCEPROP 1 LASTPIN (-175 450) BN 3
J 2
(-163 458);
DISPLAY 0.680851 (-163 458);
PAINT GREEN (-163 458);
FORCEPROP 2 LAST CDS_LIB standard
J 0
(-225 450);
DISPLAY INVISIBLE (-225 450);
FORCEPROP 1 LAST BODY_TYPE PLUMBING
J 2
(-225 500);
DISPLAY 0.872340 (-225 500);
PAINT GREEN (-225 500);
DISPLAY INVISIBLE (-225 500);
FORCEPROP 1 LAST HDL_TAP TRUE
J 2
(-550 325);
DISPLAY 0.872340 (-550 325);
DISPLAY INVISIBLE (-550 325);
FORCEPROP 1 LAST PATH I20
J 2
(-223 450);
DISPLAY 0.872340 (-223 450);
PAINT GREEN (-223 450);
DISPLAY INVISIBLE (-223 450);
FORCEADD TAP..1
R 2
(-225 400);
FORCEPROP 3 LASTPIN (-175 400) SIG_NAME M_F_CPU0_SB_DQ<2>
J 0
(-165 410);
DISPLAY 0.659574 (-165 410);
PAINT MONO (-165 410);
DISPLAY INVISIBLE (-165 410);
FORCEPROP 1 LASTPIN (-175 400) BN 2
J 2
(-163 408);
DISPLAY 0.680851 (-163 408);
PAINT GREEN (-163 408);
FORCEPROP 2 LAST CDS_LIB standard
J 0
(-225 400);
DISPLAY INVISIBLE (-225 400);
FORCEPROP 1 LAST BODY_TYPE PLUMBING
J 2
(-225 450);
DISPLAY 0.872340 (-225 450);
PAINT GREEN (-225 450);
DISPLAY INVISIBLE (-225 450);
FORCEPROP 1 LAST HDL_TAP TRUE
J 2
(-550 275);
DISPLAY 0.872340 (-550 275);
DISPLAY INVISIBLE (-550 275);
FORCEPROP 1 LAST PATH I21
J 2
(-223 400);
DISPLAY 0.872340 (-223 400);
PAINT GREEN (-223 400);
DISPLAY INVISIBLE (-223 400);
FORCEADD TAP..1
R 2
(-225 500);
FORCEPROP 3 LASTPIN (-175 500) SIG_NAME M_F_CPU0_SB_DQ<4>
J 0
(-165 510);
DISPLAY 0.659574 (-165 510);
PAINT MONO (-165 510);
DISPLAY INVISIBLE (-165 510);
FORCEPROP 1 LASTPIN (-175 500) BN 4
J 2
(-163 508);
DISPLAY 0.680851 (-163 508);
PAINT GREEN (-163 508);
FORCEPROP 2 LAST CDS_LIB standard
J 0
(-225 500);
DISPLAY INVISIBLE (-225 500);
FORCEPROP 1 LAST BODY_TYPE PLUMBING
J 2
(-225 550);
DISPLAY 0.872340 (-225 550);
PAINT GREEN (-225 550);
DISPLAY INVISIBLE (-225 550);
FORCEPROP 1 LAST HDL_TAP TRUE
J 2
(-550 375);
DISPLAY 0.872340 (-550 375);
DISPLAY INVISIBLE (-550 375);
FORCEPROP 1 LAST PATH I22
J 2
(-223 500);
DISPLAY 0.872340 (-223 500);
PAINT GREEN (-223 500);
DISPLAY INVISIBLE (-223 500);
FORCEADD TAP..1
R 2
(-225 550);
FORCEPROP 3 LASTPIN (-175 550) SIG_NAME M_F_CPU0_SB_DQ<5>
J 0
(-165 560);
DISPLAY 0.659574 (-165 560);
PAINT MONO (-165 560);
DISPLAY INVISIBLE (-165 560);
FORCEPROP 1 LASTPIN (-175 550) BN 5
J 2
(-163 558);
DISPLAY 0.680851 (-163 558);
PAINT GREEN (-163 558);
FORCEPROP 2 LAST CDS_LIB standard
J 0
(-225 550);
DISPLAY INVISIBLE (-225 550);
FORCEPROP 1 LAST BODY_TYPE PLUMBING
J 2
(-225 600);
DISPLAY 0.872340 (-225 600);
PAINT GREEN (-225 600);
DISPLAY INVISIBLE (-225 600);
FORCEPROP 1 LAST HDL_TAP TRUE
J 2
(-550 425);
DISPLAY 0.872340 (-550 425);
DISPLAY INVISIBLE (-550 425);
FORCEPROP 1 LAST PATH I23
J 2
(-223 550);
DISPLAY 0.872340 (-223 550);
PAINT GREEN (-223 550);
DISPLAY INVISIBLE (-223 550);
FORCEADD TAP..1
R 2
(-225 600);
FORCEPROP 3 LASTPIN (-175 600) SIG_NAME M_F_CPU0_SB_DQ<6>
J 0
(-165 610);
DISPLAY 0.659574 (-165 610);
PAINT MONO (-165 610);
DISPLAY INVISIBLE (-165 610);
FORCEPROP 1 LASTPIN (-175 600) BN 6
J 2
(-163 608);
DISPLAY 0.680851 (-163 608);
PAINT GREEN (-163 608);
FORCEPROP 2 LAST CDS_LIB standard
J 0
(-225 600);
DISPLAY INVISIBLE (-225 600);
FORCEPROP 1 LAST BODY_TYPE PLUMBING
J 2
(-225 650);
DISPLAY 0.872340 (-225 650);
PAINT GREEN (-225 650);
DISPLAY INVISIBLE (-225 650);
FORCEPROP 1 LAST HDL_TAP TRUE
J 2
(-550 475);
DISPLAY 0.872340 (-550 475);
DISPLAY INVISIBLE (-550 475);
FORCEPROP 1 LAST PATH I24
J 2
(-223 600);
DISPLAY 0.872340 (-223 600);
PAINT GREEN (-223 600);
DISPLAY INVISIBLE (-223 600);
FORCEADD TAP..1
R 2
(-225 700);
FORCEPROP 3 LASTPIN (-175 700) SIG_NAME M_F_CPU0_SB_DQ<8>
J 0
(-165 710);
DISPLAY 0.659574 (-165 710);
PAINT MONO (-165 710);
DISPLAY INVISIBLE (-165 710);
FORCEPROP 1 LASTPIN (-175 700) BN 8
J 2
(-163 708);
DISPLAY 0.680851 (-163 708);
PAINT GREEN (-163 708);
FORCEPROP 2 LAST CDS_LIB standard
J 0
(-225 700);
DISPLAY INVISIBLE (-225 700);
FORCEPROP 1 LAST BODY_TYPE PLUMBING
J 2
(-225 750);
DISPLAY 0.872340 (-225 750);
PAINT GREEN (-225 750);
DISPLAY INVISIBLE (-225 750);
FORCEPROP 1 LAST HDL_TAP TRUE
J 2
(-550 575);
DISPLAY 0.872340 (-550 575);
DISPLAY INVISIBLE (-550 575);
FORCEPROP 1 LAST PATH I25
J 2
(-223 700);
DISPLAY 0.872340 (-223 700);
PAINT GREEN (-223 700);
DISPLAY INVISIBLE (-223 700);
FORCEADD TAP..1
R 2
(-225 650);
FORCEPROP 3 LASTPIN (-175 650) SIG_NAME M_F_CPU0_SB_DQ<7>
J 0
(-165 660);
DISPLAY 0.659574 (-165 660);
PAINT MONO (-165 660);
DISPLAY INVISIBLE (-165 660);
FORCEPROP 1 LASTPIN (-175 650) BN 7
J 2
(-163 658);
DISPLAY 0.680851 (-163 658);
PAINT GREEN (-163 658);
FORCEPROP 2 LAST CDS_LIB standard
J 0
(-225 650);
DISPLAY INVISIBLE (-225 650);
FORCEPROP 1 LAST BODY_TYPE PLUMBING
J 2
(-225 700);
DISPLAY 0.872340 (-225 700);
PAINT GREEN (-225 700);
DISPLAY INVISIBLE (-225 700);
FORCEPROP 1 LAST HDL_TAP TRUE
J 2
(-550 525);
DISPLAY 0.872340 (-550 525);
DISPLAY INVISIBLE (-550 525);
FORCEPROP 1 LAST PATH I26
J 2
(-223 650);
DISPLAY 0.872340 (-223 650);
PAINT GREEN (-223 650);
DISPLAY INVISIBLE (-223 650);
FORCEADD TAP..1
R 2
(-225 750);
FORCEPROP 3 LASTPIN (-175 750) SIG_NAME M_F_CPU0_SB_DQ<9>
J 0
(-165 760);
DISPLAY 0.659574 (-165 760);
PAINT MONO (-165 760);
DISPLAY INVISIBLE (-165 760);
FORCEPROP 1 LASTPIN (-175 750) BN 9
J 2
(-163 758);
DISPLAY 0.680851 (-163 758);
PAINT GREEN (-163 758);
FORCEPROP 2 LAST CDS_LIB standard
J 0
(-225 750);
DISPLAY INVISIBLE (-225 750);
FORCEPROP 1 LAST BODY_TYPE PLUMBING
J 2
(-225 800);
DISPLAY 0.872340 (-225 800);
PAINT GREEN (-225 800);
DISPLAY INVISIBLE (-225 800);
FORCEPROP 1 LAST HDL_TAP TRUE
J 2
(-550 625);
DISPLAY 0.872340 (-550 625);
DISPLAY INVISIBLE (-550 625);
FORCEPROP 1 LAST PATH I27
J 2
(-223 750);
DISPLAY 0.872340 (-223 750);
PAINT GREEN (-223 750);
DISPLAY INVISIBLE (-223 750);
FORCEADD TAP..1
R 2
(-225 800);
FORCEPROP 3 LASTPIN (-175 800) SIG_NAME M_F_CPU0_SB_DQ<10>
J 0
(-165 810);
DISPLAY 0.659574 (-165 810);
PAINT MONO (-165 810);
DISPLAY INVISIBLE (-165 810);
FORCEPROP 1 LASTPIN (-175 800) BN 10
J 2
(-163 808);
DISPLAY 0.680851 (-163 808);
PAINT GREEN (-163 808);
FORCEPROP 2 LAST CDS_LIB standard
J 0
(-225 800);
DISPLAY INVISIBLE (-225 800);
FORCEPROP 1 LAST BODY_TYPE PLUMBING
J 2
(-225 850);
DISPLAY 0.872340 (-225 850);
PAINT GREEN (-225 850);
DISPLAY INVISIBLE (-225 850);
FORCEPROP 1 LAST HDL_TAP TRUE
J 2
(-550 675);
DISPLAY 0.872340 (-550 675);
DISPLAY INVISIBLE (-550 675);
FORCEPROP 1 LAST PATH I28
J 2
(-223 800);
DISPLAY 0.872340 (-223 800);
PAINT GREEN (-223 800);
DISPLAY INVISIBLE (-223 800);
FORCEADD TAP..1
R 2
(-225 850);
FORCEPROP 3 LASTPIN (-175 850) SIG_NAME M_F_CPU0_SB_DQ<11>
J 0
(-165 860);
DISPLAY 0.659574 (-165 860);
PAINT MONO (-165 860);
DISPLAY INVISIBLE (-165 860);
FORCEPROP 1 LASTPIN (-175 850) BN 11
J 2
(-163 858);
DISPLAY 0.680851 (-163 858);
PAINT GREEN (-163 858);
FORCEPROP 2 LAST CDS_LIB standard
J 0
(-225 850);
DISPLAY INVISIBLE (-225 850);
FORCEPROP 1 LAST BODY_TYPE PLUMBING
J 2
(-225 900);
DISPLAY 0.872340 (-225 900);
PAINT GREEN (-225 900);
DISPLAY INVISIBLE (-225 900);
FORCEPROP 1 LAST HDL_TAP TRUE
J 2
(-550 725);
DISPLAY 0.872340 (-550 725);
DISPLAY INVISIBLE (-550 725);
FORCEPROP 1 LAST PATH I29
J 2
(-223 850);
DISPLAY 0.872340 (-223 850);
PAINT GREEN (-223 850);
DISPLAY INVISIBLE (-223 850);
FORCEADD TAP..1
R 2
(-225 -300);
FORCEPROP 3 LASTPIN (-175 -300) SIG_NAME M_F_CPU0_CLK_DN<1>
J 0
(-165 -290);
DISPLAY 0.659574 (-165 -290);
PAINT MONO (-165 -290);
DISPLAY INVISIBLE (-165 -290);
FORCEPROP 1 LASTPIN (-175 -300) BN 1
J 2
(-163 -292);
DISPLAY 0.680851 (-163 -292);
PAINT GREEN (-163 -292);
FORCEPROP 2 LAST CDS_LIB standard
J 0
(-225 -300);
DISPLAY INVISIBLE (-225 -300);
FORCEPROP 1 LAST BODY_TYPE PLUMBING
J 2
(-225 -250);
DISPLAY 0.872340 (-225 -250);
PAINT GREEN (-225 -250);
DISPLAY INVISIBLE (-225 -250);
FORCEPROP 1 LAST HDL_TAP TRUE
J 2
(-550 -425);
DISPLAY 0.872340 (-550 -425);
DISPLAY INVISIBLE (-550 -425);
FORCEPROP 1 LAST PATH I3
J 2
(-223 -300);
DISPLAY 0.872340 (-223 -300);
PAINT GREEN (-223 -300);
DISPLAY INVISIBLE (-223 -300);
FORCEADD TAP..1
R 2
(-225 950);
FORCEPROP 3 LASTPIN (-175 950) SIG_NAME M_F_CPU0_SB_DQ<13>
J 0
(-165 960);
DISPLAY 0.659574 (-165 960);
PAINT MONO (-165 960);
DISPLAY INVISIBLE (-165 960);
FORCEPROP 1 LASTPIN (-175 950) BN 13
J 2
(-163 958);
DISPLAY 0.680851 (-163 958);
PAINT GREEN (-163 958);
FORCEPROP 2 LAST CDS_LIB standard
J 0
(-225 950);
DISPLAY INVISIBLE (-225 950);
FORCEPROP 1 LAST BODY_TYPE PLUMBING
J 2
(-225 1000);
DISPLAY 0.872340 (-225 1000);
PAINT GREEN (-225 1000);
DISPLAY INVISIBLE (-225 1000);
FORCEPROP 1 LAST HDL_TAP TRUE
J 2
(-550 825);
DISPLAY 0.872340 (-550 825);
DISPLAY INVISIBLE (-550 825);
FORCEPROP 1 LAST PATH I30
J 2
(-223 950);
DISPLAY 0.872340 (-223 950);
PAINT GREEN (-223 950);
DISPLAY INVISIBLE (-223 950);
FORCEADD TAP..1
R 2
(-225 900);
FORCEPROP 3 LASTPIN (-175 900) SIG_NAME M_F_CPU0_SB_DQ<12>
J 0
(-165 910);
DISPLAY 0.659574 (-165 910);
PAINT MONO (-165 910);
DISPLAY INVISIBLE (-165 910);
FORCEPROP 1 LASTPIN (-175 900) BN 12
J 2
(-163 908);
DISPLAY 0.680851 (-163 908);
PAINT GREEN (-163 908);
FORCEPROP 2 LAST CDS_LIB standard
J 0
(-225 900);
DISPLAY INVISIBLE (-225 900);
FORCEPROP 1 LAST BODY_TYPE PLUMBING
J 2
(-225 950);
DISPLAY 0.872340 (-225 950);
PAINT GREEN (-225 950);
DISPLAY INVISIBLE (-225 950);
FORCEPROP 1 LAST HDL_TAP TRUE
J 2
(-550 775);
DISPLAY 0.872340 (-550 775);
DISPLAY INVISIBLE (-550 775);
FORCEPROP 1 LAST PATH I31
J 2
(-223 900);
DISPLAY 0.872340 (-223 900);
PAINT GREEN (-223 900);
DISPLAY INVISIBLE (-223 900);
FORCEADD TAP..1
R 2
(-225 1000);
FORCEPROP 3 LASTPIN (-175 1000) SIG_NAME M_F_CPU0_SB_DQ<14>
J 0
(-165 1010);
DISPLAY 0.659574 (-165 1010);
PAINT MONO (-165 1010);
DISPLAY INVISIBLE (-165 1010);
FORCEPROP 1 LASTPIN (-175 1000) BN 14
J 2
(-163 1008);
DISPLAY 0.680851 (-163 1008);
PAINT GREEN (-163 1008);
FORCEPROP 2 LAST CDS_LIB standard
J 0
(-225 1000);
DISPLAY INVISIBLE (-225 1000);
FORCEPROP 1 LAST BODY_TYPE PLUMBING
J 2
(-225 1050);
DISPLAY 0.872340 (-225 1050);
PAINT GREEN (-225 1050);
DISPLAY INVISIBLE (-225 1050);
FORCEPROP 1 LAST HDL_TAP TRUE
J 2
(-550 875);
DISPLAY 0.872340 (-550 875);
DISPLAY INVISIBLE (-550 875);
FORCEPROP 1 LAST PATH I32
J 2
(-223 1000);
DISPLAY 0.872340 (-223 1000);
PAINT GREEN (-223 1000);
DISPLAY INVISIBLE (-223 1000);
FORCEADD TAP..1
R 2
(-225 1100);
FORCEPROP 3 LASTPIN (-175 1100) SIG_NAME M_F_CPU0_SB_DQ<16>
J 0
(-165 1110);
DISPLAY 0.659574 (-165 1110);
PAINT MONO (-165 1110);
DISPLAY INVISIBLE (-165 1110);
FORCEPROP 1 LASTPIN (-175 1100) BN 16
J 2
(-163 1108);
DISPLAY 0.680851 (-163 1108);
PAINT GREEN (-163 1108);
FORCEPROP 2 LAST CDS_LIB standard
J 0
(-225 1100);
DISPLAY INVISIBLE (-225 1100);
FORCEPROP 1 LAST BODY_TYPE PLUMBING
J 2
(-225 1150);
DISPLAY 0.872340 (-225 1150);
PAINT GREEN (-225 1150);
DISPLAY INVISIBLE (-225 1150);
FORCEPROP 1 LAST HDL_TAP TRUE
J 2
(-550 975);
DISPLAY 0.872340 (-550 975);
DISPLAY INVISIBLE (-550 975);
FORCEPROP 1 LAST PATH I33
J 2
(-223 1100);
DISPLAY 0.872340 (-223 1100);
PAINT GREEN (-223 1100);
DISPLAY INVISIBLE (-223 1100);
FORCEADD TAP..1
R 2
(-225 1050);
FORCEPROP 3 LASTPIN (-175 1050) SIG_NAME M_F_CPU0_SB_DQ<15>
J 0
(-165 1060);
DISPLAY 0.659574 (-165 1060);
PAINT MONO (-165 1060);
DISPLAY INVISIBLE (-165 1060);
FORCEPROP 1 LASTPIN (-175 1050) BN 15
J 2
(-163 1058);
DISPLAY 0.680851 (-163 1058);
PAINT GREEN (-163 1058);
FORCEPROP 2 LAST CDS_LIB standard
J 0
(-225 1050);
DISPLAY INVISIBLE (-225 1050);
FORCEPROP 1 LAST BODY_TYPE PLUMBING
J 2
(-225 1100);
DISPLAY 0.872340 (-225 1100);
PAINT GREEN (-225 1100);
DISPLAY INVISIBLE (-225 1100);
FORCEPROP 1 LAST HDL_TAP TRUE
J 2
(-550 925);
DISPLAY 0.872340 (-550 925);
DISPLAY INVISIBLE (-550 925);
FORCEPROP 1 LAST PATH I34
J 2
(-223 1050);
DISPLAY 0.872340 (-223 1050);
PAINT GREEN (-223 1050);
DISPLAY INVISIBLE (-223 1050);
FORCEADD TAP..1
R 2
(-225 1150);
FORCEPROP 3 LASTPIN (-175 1150) SIG_NAME M_F_CPU0_SB_DQ<17>
J 0
(-165 1160);
DISPLAY 0.659574 (-165 1160);
PAINT MONO (-165 1160);
DISPLAY INVISIBLE (-165 1160);
FORCEPROP 1 LASTPIN (-175 1150) BN 17
J 2
(-163 1158);
DISPLAY 0.680851 (-163 1158);
PAINT GREEN (-163 1158);
FORCEPROP 2 LAST CDS_LIB standard
J 0
(-225 1150);
DISPLAY INVISIBLE (-225 1150);
FORCEPROP 1 LAST BODY_TYPE PLUMBING
J 2
(-225 1200);
DISPLAY 0.872340 (-225 1200);
PAINT GREEN (-225 1200);
DISPLAY INVISIBLE (-225 1200);
FORCEPROP 1 LAST HDL_TAP TRUE
J 2
(-550 1025);
DISPLAY 0.872340 (-550 1025);
DISPLAY INVISIBLE (-550 1025);
FORCEPROP 1 LAST PATH I35
J 2
(-223 1150);
DISPLAY 0.872340 (-223 1150);
PAINT GREEN (-223 1150);
DISPLAY INVISIBLE (-223 1150);
FORCEADD TAP..1
R 2
(-225 1200);
FORCEPROP 3 LASTPIN (-175 1200) SIG_NAME M_F_CPU0_SB_DQ<18>
J 0
(-165 1210);
DISPLAY 0.659574 (-165 1210);
PAINT MONO (-165 1210);
DISPLAY INVISIBLE (-165 1210);
FORCEPROP 1 LASTPIN (-175 1200) BN 18
J 2
(-163 1208);
DISPLAY 0.680851 (-163 1208);
PAINT GREEN (-163 1208);
FORCEPROP 2 LAST CDS_LIB standard
J 0
(-225 1200);
DISPLAY INVISIBLE (-225 1200);
FORCEPROP 1 LAST BODY_TYPE PLUMBING
J 2
(-225 1250);
DISPLAY 0.872340 (-225 1250);
PAINT GREEN (-225 1250);
DISPLAY INVISIBLE (-225 1250);
FORCEPROP 1 LAST HDL_TAP TRUE
J 2
(-550 1075);
DISPLAY 0.872340 (-550 1075);
DISPLAY INVISIBLE (-550 1075);
FORCEPROP 1 LAST PATH I36
J 2
(-223 1200);
DISPLAY 0.872340 (-223 1200);
PAINT GREEN (-223 1200);
DISPLAY INVISIBLE (-223 1200);
FORCEADD TAP..1
R 2
(-225 1250);
FORCEPROP 3 LASTPIN (-175 1250) SIG_NAME M_F_CPU0_SB_DQ<19>
J 0
(-165 1260);
DISPLAY 0.659574 (-165 1260);
PAINT MONO (-165 1260);
DISPLAY INVISIBLE (-165 1260);
FORCEPROP 1 LASTPIN (-175 1250) BN 19
J 2
(-163 1258);
DISPLAY 0.680851 (-163 1258);
PAINT GREEN (-163 1258);
FORCEPROP 2 LAST CDS_LIB standard
J 0
(-225 1250);
DISPLAY INVISIBLE (-225 1250);
FORCEPROP 1 LAST BODY_TYPE PLUMBING
J 2
(-225 1300);
DISPLAY 0.872340 (-225 1300);
PAINT GREEN (-225 1300);
DISPLAY INVISIBLE (-225 1300);
FORCEPROP 1 LAST HDL_TAP TRUE
J 2
(-550 1125);
DISPLAY 0.872340 (-550 1125);
DISPLAY INVISIBLE (-550 1125);
FORCEPROP 1 LAST PATH I37
J 2
(-223 1250);
DISPLAY 0.872340 (-223 1250);
PAINT GREEN (-223 1250);
DISPLAY INVISIBLE (-223 1250);
FORCEADD TAP..1
R 2
(-225 1350);
FORCEPROP 3 LASTPIN (-175 1350) SIG_NAME M_F_CPU0_SB_DQ<21>
J 0
(-165 1360);
DISPLAY 0.659574 (-165 1360);
PAINT MONO (-165 1360);
DISPLAY INVISIBLE (-165 1360);
FORCEPROP 1 LASTPIN (-175 1350) BN 21
J 2
(-163 1358);
DISPLAY 0.680851 (-163 1358);
PAINT GREEN (-163 1358);
FORCEPROP 2 LAST CDS_LIB standard
J 0
(-225 1350);
DISPLAY INVISIBLE (-225 1350);
FORCEPROP 1 LAST BODY_TYPE PLUMBING
J 2
(-225 1400);
DISPLAY 0.872340 (-225 1400);
PAINT GREEN (-225 1400);
DISPLAY INVISIBLE (-225 1400);
FORCEPROP 1 LAST HDL_TAP TRUE
J 2
(-550 1225);
DISPLAY 0.872340 (-550 1225);
DISPLAY INVISIBLE (-550 1225);
FORCEPROP 1 LAST PATH I38
J 2
(-223 1350);
DISPLAY 0.872340 (-223 1350);
PAINT GREEN (-223 1350);
DISPLAY INVISIBLE (-223 1350);
FORCEADD TAP..1
R 2
(-225 1300);
FORCEPROP 3 LASTPIN (-175 1300) SIG_NAME M_F_CPU0_SB_DQ<20>
J 0
(-165 1310);
DISPLAY 0.659574 (-165 1310);
PAINT MONO (-165 1310);
DISPLAY INVISIBLE (-165 1310);
FORCEPROP 1 LASTPIN (-175 1300) BN 20
J 2
(-163 1308);
DISPLAY 0.680851 (-163 1308);
PAINT GREEN (-163 1308);
FORCEPROP 2 LAST CDS_LIB standard
J 0
(-225 1300);
DISPLAY INVISIBLE (-225 1300);
FORCEPROP 1 LAST BODY_TYPE PLUMBING
J 2
(-225 1350);
DISPLAY 0.872340 (-225 1350);
PAINT GREEN (-225 1350);
DISPLAY INVISIBLE (-225 1350);
FORCEPROP 1 LAST HDL_TAP TRUE
J 2
(-550 1175);
DISPLAY 0.872340 (-550 1175);
DISPLAY INVISIBLE (-550 1175);
FORCEPROP 1 LAST PATH I39
J 2
(-223 1300);
DISPLAY 0.872340 (-223 1300);
PAINT GREEN (-223 1300);
DISPLAY INVISIBLE (-223 1300);
FORCEADD TAP..1
R 2
(-225 -350);
FORCEPROP 3 LASTPIN (-175 -350) SIG_NAME M_F_CPU0_CLK_DN<0>
J 0
(-165 -340);
DISPLAY 0.659574 (-165 -340);
PAINT MONO (-165 -340);
DISPLAY INVISIBLE (-165 -340);
FORCEPROP 1 LASTPIN (-175 -350) BN 0
J 2
(-163 -342);
DISPLAY 0.680851 (-163 -342);
PAINT GREEN (-163 -342);
FORCEPROP 2 LAST CDS_LIB standard
J 0
(-225 -350);
DISPLAY INVISIBLE (-225 -350);
FORCEPROP 1 LAST BODY_TYPE PLUMBING
J 2
(-225 -300);
DISPLAY 0.872340 (-225 -300);
PAINT GREEN (-225 -300);
DISPLAY INVISIBLE (-225 -300);
FORCEPROP 1 LAST HDL_TAP TRUE
J 2
(-550 -475);
DISPLAY 0.872340 (-550 -475);
DISPLAY INVISIBLE (-550 -475);
FORCEPROP 1 LAST PATH I4
J 2
(-223 -350);
DISPLAY 0.872340 (-223 -350);
PAINT GREEN (-223 -350);
DISPLAY INVISIBLE (-223 -350);
FORCEADD TAP..1
R 2
(-225 1400);
FORCEPROP 3 LASTPIN (-175 1400) SIG_NAME M_F_CPU0_SB_DQ<22>
J 0
(-165 1410);
DISPLAY 0.659574 (-165 1410);
PAINT MONO (-165 1410);
DISPLAY INVISIBLE (-165 1410);
FORCEPROP 1 LASTPIN (-175 1400) BN 22
J 2
(-163 1408);
DISPLAY 0.680851 (-163 1408);
PAINT GREEN (-163 1408);
FORCEPROP 2 LAST CDS_LIB standard
J 0
(-225 1400);
DISPLAY INVISIBLE (-225 1400);
FORCEPROP 1 LAST BODY_TYPE PLUMBING
J 2
(-225 1450);
DISPLAY 0.872340 (-225 1450);
PAINT GREEN (-225 1450);
DISPLAY INVISIBLE (-225 1450);
FORCEPROP 1 LAST HDL_TAP TRUE
J 2
(-550 1275);
DISPLAY 0.872340 (-550 1275);
DISPLAY INVISIBLE (-550 1275);
FORCEPROP 1 LAST PATH I40
J 2
(-223 1400);
DISPLAY 0.872340 (-223 1400);
PAINT GREEN (-223 1400);
DISPLAY INVISIBLE (-223 1400);
FORCEADD TAP..1
R 2
(-225 1450);
FORCEPROP 3 LASTPIN (-175 1450) SIG_NAME M_F_CPU0_SB_DQ<23>
J 0
(-165 1460);
DISPLAY 0.659574 (-165 1460);
PAINT MONO (-165 1460);
DISPLAY INVISIBLE (-165 1460);
FORCEPROP 1 LASTPIN (-175 1450) BN 23
J 2
(-163 1458);
DISPLAY 0.680851 (-163 1458);
PAINT GREEN (-163 1458);
FORCEPROP 2 LAST CDS_LIB standard
J 0
(-225 1450);
DISPLAY INVISIBLE (-225 1450);
FORCEPROP 1 LAST BODY_TYPE PLUMBING
J 2
(-225 1500);
DISPLAY 0.872340 (-225 1500);
PAINT GREEN (-225 1500);
DISPLAY INVISIBLE (-225 1500);
FORCEPROP 1 LAST HDL_TAP TRUE
J 2
(-550 1325);
DISPLAY 0.872340 (-550 1325);
DISPLAY INVISIBLE (-550 1325);
FORCEPROP 1 LAST PATH I41
J 2
(-223 1450);
DISPLAY 0.872340 (-223 1450);
PAINT GREEN (-223 1450);
DISPLAY INVISIBLE (-223 1450);
FORCEADD TAP..1
R 2
(-225 1500);
FORCEPROP 3 LASTPIN (-175 1500) SIG_NAME M_F_CPU0_SB_DQ<24>
J 0
(-165 1510);
DISPLAY 0.659574 (-165 1510);
PAINT MONO (-165 1510);
DISPLAY INVISIBLE (-165 1510);
FORCEPROP 1 LASTPIN (-175 1500) BN 24
J 2
(-163 1508);
DISPLAY 0.680851 (-163 1508);
PAINT GREEN (-163 1508);
FORCEPROP 2 LAST CDS_LIB standard
J 0
(-225 1500);
DISPLAY INVISIBLE (-225 1500);
FORCEPROP 1 LAST BODY_TYPE PLUMBING
J 2
(-225 1550);
DISPLAY 0.872340 (-225 1550);
PAINT GREEN (-225 1550);
DISPLAY INVISIBLE (-225 1550);
FORCEPROP 1 LAST HDL_TAP TRUE
J 2
(-550 1375);
DISPLAY 0.872340 (-550 1375);
DISPLAY INVISIBLE (-550 1375);
FORCEPROP 1 LAST PATH I42
J 2
(-223 1500);
DISPLAY 0.872340 (-223 1500);
PAINT GREEN (-223 1500);
DISPLAY INVISIBLE (-223 1500);
FORCEADD TAP..1
R 2
(-225 1600);
FORCEPROP 3 LASTPIN (-175 1600) SIG_NAME M_F_CPU0_SB_DQ<26>
J 0
(-165 1610);
DISPLAY 0.659574 (-165 1610);
PAINT MONO (-165 1610);
DISPLAY INVISIBLE (-165 1610);
FORCEPROP 1 LASTPIN (-175 1600) BN 26
J 2
(-163 1608);
DISPLAY 0.680851 (-163 1608);
PAINT GREEN (-163 1608);
FORCEPROP 2 LAST CDS_LIB standard
J 0
(-225 1600);
DISPLAY INVISIBLE (-225 1600);
FORCEPROP 1 LAST BODY_TYPE PLUMBING
J 2
(-225 1650);
DISPLAY 0.872340 (-225 1650);
PAINT GREEN (-225 1650);
DISPLAY INVISIBLE (-225 1650);
FORCEPROP 1 LAST HDL_TAP TRUE
J 2
(-550 1475);
DISPLAY 0.872340 (-550 1475);
DISPLAY INVISIBLE (-550 1475);
FORCEPROP 1 LAST PATH I43
J 2
(-223 1600);
DISPLAY 0.872340 (-223 1600);
PAINT GREEN (-223 1600);
DISPLAY INVISIBLE (-223 1600);
FORCEADD TAP..1
R 2
(-225 1550);
FORCEPROP 3 LASTPIN (-175 1550) SIG_NAME M_F_CPU0_SB_DQ<25>
J 0
(-165 1560);
DISPLAY 0.659574 (-165 1560);
PAINT MONO (-165 1560);
DISPLAY INVISIBLE (-165 1560);
FORCEPROP 1 LASTPIN (-175 1550) BN 25
J 2
(-163 1558);
DISPLAY 0.680851 (-163 1558);
PAINT GREEN (-163 1558);
FORCEPROP 2 LAST CDS_LIB standard
J 0
(-225 1550);
DISPLAY INVISIBLE (-225 1550);
FORCEPROP 1 LAST BODY_TYPE PLUMBING
J 2
(-225 1600);
DISPLAY 0.872340 (-225 1600);
PAINT GREEN (-225 1600);
DISPLAY INVISIBLE (-225 1600);
FORCEPROP 1 LAST HDL_TAP TRUE
J 2
(-550 1425);
DISPLAY 0.872340 (-550 1425);
DISPLAY INVISIBLE (-550 1425);
FORCEPROP 1 LAST PATH I44
J 2
(-223 1550);
DISPLAY 0.872340 (-223 1550);
PAINT GREEN (-223 1550);
DISPLAY INVISIBLE (-223 1550);
FORCEADD TAP..1
R 2
(-225 1650);
FORCEPROP 3 LASTPIN (-175 1650) SIG_NAME M_F_CPU0_SB_DQ<27>
J 0
(-165 1660);
DISPLAY 0.659574 (-165 1660);
PAINT MONO (-165 1660);
DISPLAY INVISIBLE (-165 1660);
FORCEPROP 1 LASTPIN (-175 1650) BN 27
J 2
(-163 1658);
DISPLAY 0.680851 (-163 1658);
PAINT GREEN (-163 1658);
FORCEPROP 2 LAST CDS_LIB standard
J 0
(-225 1650);
DISPLAY INVISIBLE (-225 1650);
FORCEPROP 1 LAST BODY_TYPE PLUMBING
J 2
(-225 1700);
DISPLAY 0.872340 (-225 1700);
PAINT GREEN (-225 1700);
DISPLAY INVISIBLE (-225 1700);
FORCEPROP 1 LAST HDL_TAP TRUE
J 2
(-550 1525);
DISPLAY 0.872340 (-550 1525);
DISPLAY INVISIBLE (-550 1525);
FORCEPROP 1 LAST PATH I45
J 2
(-223 1650);
DISPLAY 0.872340 (-223 1650);
PAINT GREEN (-223 1650);
DISPLAY INVISIBLE (-223 1650);
FORCEADD TAP..1
R 2
(-225 1700);
FORCEPROP 3 LASTPIN (-175 1700) SIG_NAME M_F_CPU0_SB_DQ<28>
J 0
(-165 1710);
DISPLAY 0.659574 (-165 1710);
PAINT MONO (-165 1710);
DISPLAY INVISIBLE (-165 1710);
FORCEPROP 1 LASTPIN (-175 1700) BN 28
J 2
(-163 1708);
DISPLAY 0.680851 (-163 1708);
PAINT GREEN (-163 1708);
FORCEPROP 2 LAST CDS_LIB standard
J 0
(-225 1700);
DISPLAY INVISIBLE (-225 1700);
FORCEPROP 1 LAST BODY_TYPE PLUMBING
J 2
(-225 1750);
DISPLAY 0.872340 (-225 1750);
PAINT GREEN (-225 1750);
DISPLAY INVISIBLE (-225 1750);
FORCEPROP 1 LAST HDL_TAP TRUE
J 2
(-550 1575);
DISPLAY 0.872340 (-550 1575);
DISPLAY INVISIBLE (-550 1575);
FORCEPROP 1 LAST PATH I46
J 2
(-223 1700);
DISPLAY 0.872340 (-223 1700);
PAINT GREEN (-223 1700);
DISPLAY INVISIBLE (-223 1700);
FORCEADD TAP..1
R 2
(-225 1750);
FORCEPROP 3 LASTPIN (-175 1750) SIG_NAME M_F_CPU0_SB_DQ<29>
J 0
(-165 1760);
DISPLAY 0.659574 (-165 1760);
PAINT MONO (-165 1760);
DISPLAY INVISIBLE (-165 1760);
FORCEPROP 1 LASTPIN (-175 1750) BN 29
J 2
(-163 1758);
DISPLAY 0.680851 (-163 1758);
PAINT GREEN (-163 1758);
FORCEPROP 2 LAST CDS_LIB standard
J 0
(-225 1750);
DISPLAY INVISIBLE (-225 1750);
FORCEPROP 1 LAST BODY_TYPE PLUMBING
J 2
(-225 1800);
DISPLAY 0.872340 (-225 1800);
PAINT GREEN (-225 1800);
DISPLAY INVISIBLE (-225 1800);
FORCEPROP 1 LAST HDL_TAP TRUE
J 2
(-550 1625);
DISPLAY 0.872340 (-550 1625);
DISPLAY INVISIBLE (-550 1625);
FORCEPROP 1 LAST PATH I47
J 2
(-223 1750);
DISPLAY 0.872340 (-223 1750);
PAINT GREEN (-223 1750);
DISPLAY INVISIBLE (-223 1750);
FORCEADD TAP..1
R 2
(-225 1850);
FORCEPROP 3 LASTPIN (-175 1850) SIG_NAME M_F_CPU0_SB_DQ<31>
J 0
(-165 1860);
DISPLAY 0.659574 (-165 1860);
PAINT MONO (-165 1860);
DISPLAY INVISIBLE (-165 1860);
FORCEPROP 1 LASTPIN (-175 1850) BN 31
J 2
(-163 1858);
DISPLAY 0.680851 (-163 1858);
PAINT GREEN (-163 1858);
FORCEPROP 2 LAST CDS_LIB standard
J 0
(-225 1850);
DISPLAY INVISIBLE (-225 1850);
FORCEPROP 1 LAST BODY_TYPE PLUMBING
J 2
(-225 1900);
DISPLAY 0.872340 (-225 1900);
PAINT GREEN (-225 1900);
DISPLAY INVISIBLE (-225 1900);
FORCEPROP 1 LAST HDL_TAP TRUE
J 2
(-550 1725);
DISPLAY 0.872340 (-550 1725);
DISPLAY INVISIBLE (-550 1725);
FORCEPROP 1 LAST PATH I48
J 2
(-223 1850);
DISPLAY 0.872340 (-223 1850);
PAINT GREEN (-223 1850);
DISPLAY INVISIBLE (-223 1850);
FORCEADD TAP..1
R 2
(-225 1800);
FORCEPROP 3 LASTPIN (-175 1800) SIG_NAME M_F_CPU0_SB_DQ<30>
J 0
(-165 1810);
DISPLAY 0.659574 (-165 1810);
PAINT MONO (-165 1810);
DISPLAY INVISIBLE (-165 1810);
FORCEPROP 1 LASTPIN (-175 1800) BN 30
J 2
(-163 1808);
DISPLAY 0.680851 (-163 1808);
PAINT GREEN (-163 1808);
FORCEPROP 2 LAST CDS_LIB standard
J 0
(-225 1800);
DISPLAY INVISIBLE (-225 1800);
FORCEPROP 1 LAST BODY_TYPE PLUMBING
J 2
(-225 1850);
DISPLAY 0.872340 (-225 1850);
PAINT GREEN (-225 1850);
DISPLAY INVISIBLE (-225 1850);
FORCEPROP 1 LAST HDL_TAP TRUE
J 2
(-550 1675);
DISPLAY 0.872340 (-550 1675);
DISPLAY INVISIBLE (-550 1675);
FORCEPROP 1 LAST PATH I49
J 2
(-223 1800);
DISPLAY 0.872340 (-223 1800);
PAINT GREEN (-223 1800);
DISPLAY INVISIBLE (-223 1800);
FORCEADD TAP..1
R 2
(-225 -250);
FORCEPROP 3 LASTPIN (-175 -250) SIG_NAME M_F_CPU0_CLK_DP<0>
J 0
(-165 -240);
DISPLAY 0.659574 (-165 -240);
PAINT MONO (-165 -240);
DISPLAY INVISIBLE (-165 -240);
FORCEPROP 1 LASTPIN (-175 -250) BN 0
J 2
(-163 -242);
DISPLAY 0.680851 (-163 -242);
PAINT GREEN (-163 -242);
FORCEPROP 2 LAST CDS_LIB standard
J 0
(-225 -250);
DISPLAY INVISIBLE (-225 -250);
FORCEPROP 1 LAST BODY_TYPE PLUMBING
J 2
(-225 -200);
DISPLAY 0.872340 (-225 -200);
PAINT GREEN (-225 -200);
DISPLAY INVISIBLE (-225 -200);
FORCEPROP 1 LAST HDL_TAP TRUE
J 2
(-550 -375);
DISPLAY 0.872340 (-550 -375);
DISPLAY INVISIBLE (-550 -375);
FORCEPROP 1 LAST PATH I5
J 2
(-223 -250);
DISPLAY 0.872340 (-223 -250);
PAINT GREEN (-223 -250);
DISPLAY INVISIBLE (-223 -250);
FORCEADD OFFPAGE..3
R 2
(-1250 2275);
FORCEPROP 2 LAST $XR1 93 
J 0
(-1619 2275);
DISPLAY 0.638298 (-1619 2275);
PAINT MONO (-1619 2275);
FORCEPROP 2 LAST $XR0 92 
J 0
(-1529 2275);
DISPLAY 0.638298 (-1529 2275);
PAINT MONO (-1529 2275);
FORCEPROP 2 LAST CDS_LIB standard
J 0
(-1250 2275);
DISPLAY INVISIBLE (-1250 2275);
FORCEPROP 1 LAST OFFPAGE TRUE
J 2
(-1575 2150);
DISPLAY 0.872340 (-1575 2150);
DISPLAY INVISIBLE (-1575 2150);
FORCEPROP 1 LAST COMMENT_BODY TRUE
J 2
(-1200 2175);
DISPLAY 0.872340 (-1200 2175);
PAINT GREEN (-1200 2175);
DISPLAY INVISIBLE (-1200 2175);
FORCEPROP 2 LAST PATH I50
J 0
(-1200 2350);
DISPLAY 1.021277 (-1200 2350);
DISPLAY INVISIBLE (-1200 2350);
FORCEADD OFFPAGE..3
R 2
(-1250 3875);
FORCEPROP 2 LAST $XR1 93 
J 0
(-1619 3875);
DISPLAY 0.638298 (-1619 3875);
PAINT MONO (-1619 3875);
FORCEPROP 2 LAST $XR0 92 
J 0
(-1529 3875);
DISPLAY 0.638298 (-1529 3875);
PAINT MONO (-1529 3875);
FORCEPROP 2 LAST CDS_LIB standard
J 0
(-1250 3875);
DISPLAY INVISIBLE (-1250 3875);
FORCEPROP 1 LAST OFFPAGE TRUE
J 2
(-1575 3750);
DISPLAY 0.872340 (-1575 3750);
DISPLAY INVISIBLE (-1575 3750);
FORCEPROP 1 LAST COMMENT_BODY TRUE
J 2
(-1200 3775);
DISPLAY 0.872340 (-1200 3775);
PAINT GREEN (-1200 3775);
DISPLAY INVISIBLE (-1200 3775);
FORCEPROP 2 LAST PATH I51
J 0
(-1200 3950);
DISPLAY 1.021277 (-1200 3950);
DISPLAY INVISIBLE (-1200 3950);
FORCEADD TAP..1
R 2
(-225 2000);
FORCEPROP 3 LASTPIN (-175 2000) SIG_NAME M_F_CPU0_SA_CB<2>
J 0
(-165 2010);
DISPLAY 0.659574 (-165 2010);
PAINT MONO (-165 2010);
DISPLAY INVISIBLE (-165 2010);
FORCEPROP 1 LASTPIN (-175 2000) BN 2
J 2
(-163 2008);
DISPLAY 0.680851 (-163 2008);
PAINT GREEN (-163 2008);
FORCEPROP 2 LAST CDS_LIB standard
J 0
(-225 2000);
DISPLAY INVISIBLE (-225 2000);
FORCEPROP 1 LAST BODY_TYPE PLUMBING
J 2
(-225 2050);
DISPLAY 0.872340 (-225 2050);
PAINT GREEN (-225 2050);
DISPLAY INVISIBLE (-225 2050);
FORCEPROP 1 LAST HDL_TAP TRUE
J 2
(-550 1875);
DISPLAY 0.872340 (-550 1875);
DISPLAY INVISIBLE (-550 1875);
FORCEPROP 1 LAST PATH I52
J 2
(-223 2000);
DISPLAY 0.872340 (-223 2000);
PAINT GREEN (-223 2000);
DISPLAY INVISIBLE (-223 2000);
FORCEADD TAP..1
R 2
(-225 1900);
FORCEPROP 3 LASTPIN (-175 1900) SIG_NAME M_F_CPU0_SA_CB<0>
J 0
(-165 1910);
DISPLAY 0.659574 (-165 1910);
PAINT MONO (-165 1910);
DISPLAY INVISIBLE (-165 1910);
FORCEPROP 1 LASTPIN (-175 1900) BN 0
J 2
(-163 1908);
DISPLAY 0.680851 (-163 1908);
PAINT GREEN (-163 1908);
FORCEPROP 2 LAST CDS_LIB standard
J 0
(-225 1900);
DISPLAY INVISIBLE (-225 1900);
FORCEPROP 1 LAST BODY_TYPE PLUMBING
J 2
(-225 1950);
DISPLAY 0.872340 (-225 1950);
PAINT GREEN (-225 1950);
DISPLAY INVISIBLE (-225 1950);
FORCEPROP 1 LAST HDL_TAP TRUE
J 2
(-550 1775);
DISPLAY 0.872340 (-550 1775);
DISPLAY INVISIBLE (-550 1775);
FORCEPROP 1 LAST PATH I53
J 2
(-223 1900);
DISPLAY 0.872340 (-223 1900);
PAINT GREEN (-223 1900);
DISPLAY INVISIBLE (-223 1900);
FORCEADD TAP..1
R 2
(-225 1950);
FORCEPROP 3 LASTPIN (-175 1950) SIG_NAME M_F_CPU0_SA_CB<1>
J 0
(-165 1960);
DISPLAY 0.659574 (-165 1960);
PAINT MONO (-165 1960);
DISPLAY INVISIBLE (-165 1960);
FORCEPROP 1 LASTPIN (-175 1950) BN 1
J 2
(-163 1958);
DISPLAY 0.680851 (-163 1958);
PAINT GREEN (-163 1958);
FORCEPROP 2 LAST CDS_LIB standard
J 0
(-225 1950);
DISPLAY INVISIBLE (-225 1950);
FORCEPROP 1 LAST BODY_TYPE PLUMBING
J 2
(-225 2000);
DISPLAY 0.872340 (-225 2000);
PAINT GREEN (-225 2000);
DISPLAY INVISIBLE (-225 2000);
FORCEPROP 1 LAST HDL_TAP TRUE
J 2
(-550 1825);
DISPLAY 0.872340 (-550 1825);
DISPLAY INVISIBLE (-550 1825);
FORCEPROP 1 LAST PATH I54
J 2
(-223 1950);
DISPLAY 0.872340 (-223 1950);
PAINT GREEN (-223 1950);
DISPLAY INVISIBLE (-223 1950);
FORCEADD TAP..1
R 2
(-225 2050);
FORCEPROP 3 LASTPIN (-175 2050) SIG_NAME M_F_CPU0_SA_CB<3>
J 0
(-165 2060);
DISPLAY 0.659574 (-165 2060);
PAINT MONO (-165 2060);
DISPLAY INVISIBLE (-165 2060);
FORCEPROP 1 LASTPIN (-175 2050) BN 3
J 2
(-163 2058);
DISPLAY 0.680851 (-163 2058);
PAINT GREEN (-163 2058);
FORCEPROP 2 LAST CDS_LIB standard
J 0
(-225 2050);
DISPLAY INVISIBLE (-225 2050);
FORCEPROP 1 LAST BODY_TYPE PLUMBING
J 2
(-225 2100);
DISPLAY 0.872340 (-225 2100);
PAINT GREEN (-225 2100);
DISPLAY INVISIBLE (-225 2100);
FORCEPROP 1 LAST HDL_TAP TRUE
J 2
(-550 1925);
DISPLAY 0.872340 (-550 1925);
DISPLAY INVISIBLE (-550 1925);
FORCEPROP 1 LAST PATH I55
J 2
(-223 2050);
DISPLAY 0.872340 (-223 2050);
PAINT GREEN (-223 2050);
DISPLAY INVISIBLE (-223 2050);
FORCEADD TAP..1
R 2
(-225 2100);
FORCEPROP 3 LASTPIN (-175 2100) SIG_NAME M_F_CPU0_SA_CB<4>
J 0
(-165 2110);
DISPLAY 0.659574 (-165 2110);
PAINT MONO (-165 2110);
DISPLAY INVISIBLE (-165 2110);
FORCEPROP 1 LASTPIN (-175 2100) BN 4
J 2
(-163 2108);
DISPLAY 0.680851 (-163 2108);
PAINT GREEN (-163 2108);
FORCEPROP 2 LAST CDS_LIB standard
J 0
(-225 2100);
DISPLAY INVISIBLE (-225 2100);
FORCEPROP 1 LAST BODY_TYPE PLUMBING
J 2
(-225 2150);
DISPLAY 0.872340 (-225 2150);
PAINT GREEN (-225 2150);
DISPLAY INVISIBLE (-225 2150);
FORCEPROP 1 LAST HDL_TAP TRUE
J 2
(-550 1975);
DISPLAY 0.872340 (-550 1975);
DISPLAY INVISIBLE (-550 1975);
FORCEPROP 1 LAST PATH I56
J 2
(-223 2100);
DISPLAY 0.872340 (-223 2100);
PAINT GREEN (-223 2100);
DISPLAY INVISIBLE (-223 2100);
FORCEADD TAP..1
R 2
(-225 2150);
FORCEPROP 3 LASTPIN (-175 2150) SIG_NAME M_F_CPU0_SA_CB<5>
J 0
(-165 2160);
DISPLAY 0.659574 (-165 2160);
PAINT MONO (-165 2160);
DISPLAY INVISIBLE (-165 2160);
FORCEPROP 1 LASTPIN (-175 2150) BN 5
J 2
(-163 2158);
DISPLAY 0.680851 (-163 2158);
PAINT GREEN (-163 2158);
FORCEPROP 2 LAST CDS_LIB standard
J 0
(-225 2150);
DISPLAY INVISIBLE (-225 2150);
FORCEPROP 1 LAST BODY_TYPE PLUMBING
J 2
(-225 2200);
DISPLAY 0.872340 (-225 2200);
PAINT GREEN (-225 2200);
DISPLAY INVISIBLE (-225 2200);
FORCEPROP 1 LAST HDL_TAP TRUE
J 2
(-550 2025);
DISPLAY 0.872340 (-550 2025);
DISPLAY INVISIBLE (-550 2025);
FORCEPROP 1 LAST PATH I57
J 2
(-223 2150);
DISPLAY 0.872340 (-223 2150);
PAINT GREEN (-223 2150);
DISPLAY INVISIBLE (-223 2150);
FORCEADD TAP..1
R 2
(-225 2250);
FORCEPROP 3 LASTPIN (-175 2250) SIG_NAME M_F_CPU0_SA_CB<7>
J 0
(-165 2260);
DISPLAY 0.659574 (-165 2260);
PAINT MONO (-165 2260);
DISPLAY INVISIBLE (-165 2260);
FORCEPROP 1 LASTPIN (-175 2250) BN 7
J 2
(-163 2258);
DISPLAY 0.680851 (-163 2258);
PAINT GREEN (-163 2258);
FORCEPROP 2 LAST CDS_LIB standard
J 0
(-225 2250);
DISPLAY INVISIBLE (-225 2250);
FORCEPROP 1 LAST BODY_TYPE PLUMBING
J 2
(-225 2300);
DISPLAY 0.872340 (-225 2300);
PAINT GREEN (-225 2300);
DISPLAY INVISIBLE (-225 2300);
FORCEPROP 1 LAST HDL_TAP TRUE
J 2
(-550 2125);
DISPLAY 0.872340 (-550 2125);
DISPLAY INVISIBLE (-550 2125);
FORCEPROP 1 LAST PATH I58
J 2
(-223 2250);
DISPLAY 0.872340 (-223 2250);
PAINT GREEN (-223 2250);
DISPLAY INVISIBLE (-223 2250);
FORCEADD TAP..1
R 2
(-225 2200);
FORCEPROP 3 LASTPIN (-175 2200) SIG_NAME M_F_CPU0_SA_CB<6>
J 0
(-165 2210);
DISPLAY 0.659574 (-165 2210);
PAINT MONO (-165 2210);
DISPLAY INVISIBLE (-165 2210);
FORCEPROP 1 LASTPIN (-175 2200) BN 6
J 2
(-163 2208);
DISPLAY 0.680851 (-163 2208);
PAINT GREEN (-163 2208);
FORCEPROP 2 LAST CDS_LIB standard
J 0
(-225 2200);
DISPLAY INVISIBLE (-225 2200);
FORCEPROP 1 LAST BODY_TYPE PLUMBING
J 2
(-225 2250);
DISPLAY 0.872340 (-225 2250);
PAINT GREEN (-225 2250);
DISPLAY INVISIBLE (-225 2250);
FORCEPROP 1 LAST HDL_TAP TRUE
J 2
(-550 2075);
DISPLAY 0.872340 (-550 2075);
DISPLAY INVISIBLE (-550 2075);
FORCEPROP 1 LAST PATH I59
J 2
(-223 2200);
DISPLAY 0.872340 (-223 2200);
PAINT GREEN (-223 2200);
DISPLAY INVISIBLE (-223 2200);
FORCEADD TAP..1
R 2
(-225 -200);
FORCEPROP 3 LASTPIN (-175 -200) SIG_NAME M_F_CPU0_CLK_DP<1>
J 0
(-165 -190);
DISPLAY 0.659574 (-165 -190);
PAINT MONO (-165 -190);
DISPLAY INVISIBLE (-165 -190);
FORCEPROP 1 LASTPIN (-175 -200) BN 1
J 2
(-163 -192);
DISPLAY 0.680851 (-163 -192);
PAINT GREEN (-163 -192);
FORCEPROP 2 LAST CDS_LIB standard
J 0
(-225 -200);
DISPLAY INVISIBLE (-225 -200);
FORCEPROP 1 LAST BODY_TYPE PLUMBING
J 2
(-225 -150);
DISPLAY 0.872340 (-225 -150);
PAINT GREEN (-225 -150);
DISPLAY INVISIBLE (-225 -150);
FORCEPROP 1 LAST HDL_TAP TRUE
J 2
(-550 -325);
DISPLAY 0.872340 (-550 -325);
DISPLAY INVISIBLE (-550 -325);
FORCEPROP 1 LAST PATH I6
J 2
(-223 -200);
DISPLAY 0.872340 (-223 -200);
PAINT GREEN (-223 -200);
DISPLAY INVISIBLE (-223 -200);
FORCEADD TAP..1
R 2
(-225 2350);
FORCEPROP 3 LASTPIN (-175 2350) SIG_NAME M_F_CPU0_SA_DQ<1>
J 0
(-165 2360);
DISPLAY 0.659574 (-165 2360);
PAINT MONO (-165 2360);
DISPLAY INVISIBLE (-165 2360);
FORCEPROP 1 LASTPIN (-175 2350) BN 1
J 2
(-163 2358);
DISPLAY 0.680851 (-163 2358);
PAINT GREEN (-163 2358);
FORCEPROP 2 LAST CDS_LIB standard
J 0
(-225 2350);
DISPLAY INVISIBLE (-225 2350);
FORCEPROP 1 LAST BODY_TYPE PLUMBING
J 2
(-225 2400);
DISPLAY 0.872340 (-225 2400);
PAINT GREEN (-225 2400);
DISPLAY INVISIBLE (-225 2400);
FORCEPROP 1 LAST HDL_TAP TRUE
J 2
(-550 2225);
DISPLAY 0.872340 (-550 2225);
DISPLAY INVISIBLE (-550 2225);
FORCEPROP 1 LAST PATH I60
J 2
(-223 2350);
DISPLAY 0.872340 (-223 2350);
PAINT GREEN (-223 2350);
DISPLAY INVISIBLE (-223 2350);
FORCEADD TAP..1
R 2
(-225 2300);
FORCEPROP 3 LASTPIN (-175 2300) SIG_NAME M_F_CPU0_SA_DQ<0>
J 0
(-165 2310);
DISPLAY 0.659574 (-165 2310);
PAINT MONO (-165 2310);
DISPLAY INVISIBLE (-165 2310);
FORCEPROP 1 LASTPIN (-175 2300) BN 0
J 2
(-163 2308);
DISPLAY 0.680851 (-163 2308);
PAINT GREEN (-163 2308);
FORCEPROP 2 LAST CDS_LIB standard
J 0
(-225 2300);
DISPLAY INVISIBLE (-225 2300);
FORCEPROP 1 LAST BODY_TYPE PLUMBING
J 2
(-225 2350);
DISPLAY 0.872340 (-225 2350);
PAINT GREEN (-225 2350);
DISPLAY INVISIBLE (-225 2350);
FORCEPROP 1 LAST HDL_TAP TRUE
J 2
(-550 2175);
DISPLAY 0.872340 (-550 2175);
DISPLAY INVISIBLE (-550 2175);
FORCEPROP 1 LAST PATH I61
J 2
(-223 2300);
DISPLAY 0.872340 (-223 2300);
PAINT GREEN (-223 2300);
DISPLAY INVISIBLE (-223 2300);
FORCEADD TAP..1
R 2
(-225 2400);
FORCEPROP 3 LASTPIN (-175 2400) SIG_NAME M_F_CPU0_SA_DQ<2>
J 0
(-165 2410);
DISPLAY 0.659574 (-165 2410);
PAINT MONO (-165 2410);
DISPLAY INVISIBLE (-165 2410);
FORCEPROP 1 LASTPIN (-175 2400) BN 2
J 2
(-163 2408);
DISPLAY 0.680851 (-163 2408);
PAINT GREEN (-163 2408);
FORCEPROP 2 LAST CDS_LIB standard
J 0
(-225 2400);
DISPLAY INVISIBLE (-225 2400);
FORCEPROP 1 LAST BODY_TYPE PLUMBING
J 2
(-225 2450);
DISPLAY 0.872340 (-225 2450);
PAINT GREEN (-225 2450);
DISPLAY INVISIBLE (-225 2450);
FORCEPROP 1 LAST HDL_TAP TRUE
J 2
(-550 2275);
DISPLAY 0.872340 (-550 2275);
DISPLAY INVISIBLE (-550 2275);
FORCEPROP 1 LAST PATH I62
J 2
(-223 2400);
DISPLAY 0.872340 (-223 2400);
PAINT GREEN (-223 2400);
DISPLAY INVISIBLE (-223 2400);
FORCEADD TAP..1
R 2
(-225 2500);
FORCEPROP 3 LASTPIN (-175 2500) SIG_NAME M_F_CPU0_SA_DQ<4>
J 0
(-165 2510);
DISPLAY 0.659574 (-165 2510);
PAINT MONO (-165 2510);
DISPLAY INVISIBLE (-165 2510);
FORCEPROP 1 LASTPIN (-175 2500) BN 4
J 2
(-163 2508);
DISPLAY 0.680851 (-163 2508);
PAINT GREEN (-163 2508);
FORCEPROP 2 LAST CDS_LIB standard
J 0
(-225 2500);
DISPLAY INVISIBLE (-225 2500);
FORCEPROP 1 LAST BODY_TYPE PLUMBING
J 2
(-225 2550);
DISPLAY 0.872340 (-225 2550);
PAINT GREEN (-225 2550);
DISPLAY INVISIBLE (-225 2550);
FORCEPROP 1 LAST HDL_TAP TRUE
J 2
(-550 2375);
DISPLAY 0.872340 (-550 2375);
DISPLAY INVISIBLE (-550 2375);
FORCEPROP 1 LAST PATH I63
J 2
(-223 2500);
DISPLAY 0.872340 (-223 2500);
PAINT GREEN (-223 2500);
DISPLAY INVISIBLE (-223 2500);
FORCEADD TAP..1
R 2
(-225 2450);
FORCEPROP 3 LASTPIN (-175 2450) SIG_NAME M_F_CPU0_SA_DQ<3>
J 0
(-165 2460);
DISPLAY 0.659574 (-165 2460);
PAINT MONO (-165 2460);
DISPLAY INVISIBLE (-165 2460);
FORCEPROP 1 LASTPIN (-175 2450) BN 3
J 2
(-163 2458);
DISPLAY 0.680851 (-163 2458);
PAINT GREEN (-163 2458);
FORCEPROP 2 LAST CDS_LIB standard
J 0
(-225 2450);
DISPLAY INVISIBLE (-225 2450);
FORCEPROP 1 LAST BODY_TYPE PLUMBING
J 2
(-225 2500);
DISPLAY 0.872340 (-225 2500);
PAINT GREEN (-225 2500);
DISPLAY INVISIBLE (-225 2500);
FORCEPROP 1 LAST HDL_TAP TRUE
J 2
(-550 2325);
DISPLAY 0.872340 (-550 2325);
DISPLAY INVISIBLE (-550 2325);
FORCEPROP 1 LAST PATH I64
J 2
(-223 2450);
DISPLAY 0.872340 (-223 2450);
PAINT GREEN (-223 2450);
DISPLAY INVISIBLE (-223 2450);
FORCEADD TAP..1
R 2
(-225 2550);
FORCEPROP 3 LASTPIN (-175 2550) SIG_NAME M_F_CPU0_SA_DQ<5>
J 0
(-165 2560);
DISPLAY 0.659574 (-165 2560);
PAINT MONO (-165 2560);
DISPLAY INVISIBLE (-165 2560);
FORCEPROP 1 LASTPIN (-175 2550) BN 5
J 2
(-163 2558);
DISPLAY 0.680851 (-163 2558);
PAINT GREEN (-163 2558);
FORCEPROP 2 LAST CDS_LIB standard
J 0
(-225 2550);
DISPLAY INVISIBLE (-225 2550);
FORCEPROP 1 LAST BODY_TYPE PLUMBING
J 2
(-225 2600);
DISPLAY 0.872340 (-225 2600);
PAINT GREEN (-225 2600);
DISPLAY INVISIBLE (-225 2600);
FORCEPROP 1 LAST HDL_TAP TRUE
J 2
(-550 2425);
DISPLAY 0.872340 (-550 2425);
DISPLAY INVISIBLE (-550 2425);
FORCEPROP 1 LAST PATH I65
J 2
(-223 2550);
DISPLAY 0.872340 (-223 2550);
PAINT GREEN (-223 2550);
DISPLAY INVISIBLE (-223 2550);
FORCEADD TAP..1
R 2
(-225 2600);
FORCEPROP 3 LASTPIN (-175 2600) SIG_NAME M_F_CPU0_SA_DQ<6>
J 0
(-165 2610);
DISPLAY 0.659574 (-165 2610);
PAINT MONO (-165 2610);
DISPLAY INVISIBLE (-165 2610);
FORCEPROP 1 LASTPIN (-175 2600) BN 6
J 2
(-163 2608);
DISPLAY 0.680851 (-163 2608);
PAINT GREEN (-163 2608);
FORCEPROP 2 LAST CDS_LIB standard
J 0
(-225 2600);
DISPLAY INVISIBLE (-225 2600);
FORCEPROP 1 LAST BODY_TYPE PLUMBING
J 2
(-225 2650);
DISPLAY 0.872340 (-225 2650);
PAINT GREEN (-225 2650);
DISPLAY INVISIBLE (-225 2650);
FORCEPROP 1 LAST HDL_TAP TRUE
J 2
(-550 2475);
DISPLAY 0.872340 (-550 2475);
DISPLAY INVISIBLE (-550 2475);
FORCEPROP 1 LAST PATH I66
J 2
(-223 2600);
DISPLAY 0.872340 (-223 2600);
PAINT GREEN (-223 2600);
DISPLAY INVISIBLE (-223 2600);
FORCEADD TAP..1
R 2
(-225 2650);
FORCEPROP 3 LASTPIN (-175 2650) SIG_NAME M_F_CPU0_SA_DQ<7>
J 0
(-165 2660);
DISPLAY 0.659574 (-165 2660);
PAINT MONO (-165 2660);
DISPLAY INVISIBLE (-165 2660);
FORCEPROP 1 LASTPIN (-175 2650) BN 7
J 2
(-163 2658);
DISPLAY 0.680851 (-163 2658);
PAINT GREEN (-163 2658);
FORCEPROP 2 LAST CDS_LIB standard
J 0
(-225 2650);
DISPLAY INVISIBLE (-225 2650);
FORCEPROP 1 LAST BODY_TYPE PLUMBING
J 2
(-225 2700);
DISPLAY 0.872340 (-225 2700);
PAINT GREEN (-225 2700);
DISPLAY INVISIBLE (-225 2700);
FORCEPROP 1 LAST HDL_TAP TRUE
J 2
(-550 2525);
DISPLAY 0.872340 (-550 2525);
DISPLAY INVISIBLE (-550 2525);
FORCEPROP 1 LAST PATH I67
J 2
(-223 2650);
DISPLAY 0.872340 (-223 2650);
PAINT GREEN (-223 2650);
DISPLAY INVISIBLE (-223 2650);
FORCEADD TAP..1
R 2
(-225 2750);
FORCEPROP 3 LASTPIN (-175 2750) SIG_NAME M_F_CPU0_SA_DQ<9>
J 0
(-165 2760);
DISPLAY 0.659574 (-165 2760);
PAINT MONO (-165 2760);
DISPLAY INVISIBLE (-165 2760);
FORCEPROP 1 LASTPIN (-175 2750) BN 9
J 2
(-163 2758);
DISPLAY 0.680851 (-163 2758);
PAINT GREEN (-163 2758);
FORCEPROP 2 LAST CDS_LIB standard
J 0
(-225 2750);
DISPLAY INVISIBLE (-225 2750);
FORCEPROP 1 LAST BODY_TYPE PLUMBING
J 2
(-225 2800);
DISPLAY 0.872340 (-225 2800);
PAINT GREEN (-225 2800);
DISPLAY INVISIBLE (-225 2800);
FORCEPROP 1 LAST HDL_TAP TRUE
J 2
(-550 2625);
DISPLAY 0.872340 (-550 2625);
DISPLAY INVISIBLE (-550 2625);
FORCEPROP 1 LAST PATH I68
J 2
(-223 2750);
DISPLAY 0.872340 (-223 2750);
PAINT GREEN (-223 2750);
DISPLAY INVISIBLE (-223 2750);
FORCEADD TAP..1
R 2
(-225 2700);
FORCEPROP 3 LASTPIN (-175 2700) SIG_NAME M_F_CPU0_SA_DQ<8>
J 0
(-165 2710);
DISPLAY 0.659574 (-165 2710);
PAINT MONO (-165 2710);
DISPLAY INVISIBLE (-165 2710);
FORCEPROP 1 LASTPIN (-175 2700) BN 8
J 2
(-163 2708);
DISPLAY 0.680851 (-163 2708);
PAINT GREEN (-163 2708);
FORCEPROP 2 LAST CDS_LIB standard
J 0
(-225 2700);
DISPLAY INVISIBLE (-225 2700);
FORCEPROP 1 LAST BODY_TYPE PLUMBING
J 2
(-225 2750);
DISPLAY 0.872340 (-225 2750);
PAINT GREEN (-225 2750);
DISPLAY INVISIBLE (-225 2750);
FORCEPROP 1 LAST HDL_TAP TRUE
J 2
(-550 2575);
DISPLAY 0.872340 (-550 2575);
DISPLAY INVISIBLE (-550 2575);
FORCEPROP 1 LAST PATH I69
J 2
(-223 2700);
DISPLAY 0.872340 (-223 2700);
PAINT GREEN (-223 2700);
DISPLAY INVISIBLE (-223 2700);
FORCEADD TAP..1
R 2
(-225 2800);
FORCEPROP 3 LASTPIN (-175 2800) SIG_NAME M_F_CPU0_SA_DQ<10>
J 0
(-165 2810);
DISPLAY 0.659574 (-165 2810);
PAINT MONO (-165 2810);
DISPLAY INVISIBLE (-165 2810);
FORCEPROP 1 LASTPIN (-175 2800) BN 10
J 2
(-163 2808);
DISPLAY 0.680851 (-163 2808);
PAINT GREEN (-163 2808);
FORCEPROP 2 LAST CDS_LIB standard
J 0
(-225 2800);
DISPLAY INVISIBLE (-225 2800);
FORCEPROP 1 LAST BODY_TYPE PLUMBING
J 2
(-225 2850);
DISPLAY 0.872340 (-225 2850);
PAINT GREEN (-225 2850);
DISPLAY INVISIBLE (-225 2850);
FORCEPROP 1 LAST HDL_TAP TRUE
J 2
(-550 2675);
DISPLAY 0.872340 (-550 2675);
DISPLAY INVISIBLE (-550 2675);
FORCEPROP 1 LAST PATH I70
J 2
(-223 2800);
DISPLAY 0.872340 (-223 2800);
PAINT GREEN (-223 2800);
DISPLAY INVISIBLE (-223 2800);
FORCEADD TAP..1
R 2
(-225 2850);
FORCEPROP 3 LASTPIN (-175 2850) SIG_NAME M_F_CPU0_SA_DQ<11>
J 0
(-165 2860);
DISPLAY 0.659574 (-165 2860);
PAINT MONO (-165 2860);
DISPLAY INVISIBLE (-165 2860);
FORCEPROP 1 LASTPIN (-175 2850) BN 11
J 2
(-163 2858);
DISPLAY 0.680851 (-163 2858);
PAINT GREEN (-163 2858);
FORCEPROP 2 LAST CDS_LIB standard
J 0
(-225 2850);
DISPLAY INVISIBLE (-225 2850);
FORCEPROP 1 LAST BODY_TYPE PLUMBING
J 2
(-225 2900);
DISPLAY 0.872340 (-225 2900);
PAINT GREEN (-225 2900);
DISPLAY INVISIBLE (-225 2900);
FORCEPROP 1 LAST HDL_TAP TRUE
J 2
(-550 2725);
DISPLAY 0.872340 (-550 2725);
DISPLAY INVISIBLE (-550 2725);
FORCEPROP 1 LAST PATH I71
J 2
(-223 2850);
DISPLAY 0.872340 (-223 2850);
PAINT GREEN (-223 2850);
DISPLAY INVISIBLE (-223 2850);
FORCEADD TAP..1
R 2
(-225 2900);
FORCEPROP 3 LASTPIN (-175 2900) SIG_NAME M_F_CPU0_SA_DQ<12>
J 0
(-165 2910);
DISPLAY 0.659574 (-165 2910);
PAINT MONO (-165 2910);
DISPLAY INVISIBLE (-165 2910);
FORCEPROP 1 LASTPIN (-175 2900) BN 12
J 2
(-163 2908);
DISPLAY 0.680851 (-163 2908);
PAINT GREEN (-163 2908);
FORCEPROP 2 LAST CDS_LIB standard
J 0
(-225 2900);
DISPLAY INVISIBLE (-225 2900);
FORCEPROP 1 LAST BODY_TYPE PLUMBING
J 2
(-225 2950);
DISPLAY 0.872340 (-225 2950);
PAINT GREEN (-225 2950);
DISPLAY INVISIBLE (-225 2950);
FORCEPROP 1 LAST HDL_TAP TRUE
J 2
(-550 2775);
DISPLAY 0.872340 (-550 2775);
DISPLAY INVISIBLE (-550 2775);
FORCEPROP 1 LAST PATH I72
J 2
(-223 2900);
DISPLAY 0.872340 (-223 2900);
PAINT GREEN (-223 2900);
DISPLAY INVISIBLE (-223 2900);
FORCEADD TAP..1
R 2
(-225 3000);
FORCEPROP 3 LASTPIN (-175 3000) SIG_NAME M_F_CPU0_SA_DQ<14>
J 0
(-165 3010);
DISPLAY 0.659574 (-165 3010);
PAINT MONO (-165 3010);
DISPLAY INVISIBLE (-165 3010);
FORCEPROP 1 LASTPIN (-175 3000) BN 14
J 2
(-163 3008);
DISPLAY 0.680851 (-163 3008);
PAINT GREEN (-163 3008);
FORCEPROP 2 LAST CDS_LIB standard
J 0
(-225 3000);
DISPLAY INVISIBLE (-225 3000);
FORCEPROP 1 LAST BODY_TYPE PLUMBING
J 2
(-225 3050);
DISPLAY 0.872340 (-225 3050);
PAINT GREEN (-225 3050);
DISPLAY INVISIBLE (-225 3050);
FORCEPROP 1 LAST HDL_TAP TRUE
J 2
(-550 2875);
DISPLAY 0.872340 (-550 2875);
DISPLAY INVISIBLE (-550 2875);
FORCEPROP 1 LAST PATH I73
J 2
(-223 3000);
DISPLAY 0.872340 (-223 3000);
PAINT GREEN (-223 3000);
DISPLAY INVISIBLE (-223 3000);
FORCEADD TAP..1
R 2
(-225 2950);
FORCEPROP 3 LASTPIN (-175 2950) SIG_NAME M_F_CPU0_SA_DQ<13>
J 0
(-165 2960);
DISPLAY 0.659574 (-165 2960);
PAINT MONO (-165 2960);
DISPLAY INVISIBLE (-165 2960);
FORCEPROP 1 LASTPIN (-175 2950) BN 13
J 2
(-163 2958);
DISPLAY 0.680851 (-163 2958);
PAINT GREEN (-163 2958);
FORCEPROP 2 LAST CDS_LIB standard
J 0
(-225 2950);
DISPLAY INVISIBLE (-225 2950);
FORCEPROP 1 LAST BODY_TYPE PLUMBING
J 2
(-225 3000);
DISPLAY 0.872340 (-225 3000);
PAINT GREEN (-225 3000);
DISPLAY INVISIBLE (-225 3000);
FORCEPROP 1 LAST HDL_TAP TRUE
J 2
(-550 2825);
DISPLAY 0.872340 (-550 2825);
DISPLAY INVISIBLE (-550 2825);
FORCEPROP 1 LAST PATH I74
J 2
(-223 2950);
DISPLAY 0.872340 (-223 2950);
PAINT GREEN (-223 2950);
DISPLAY INVISIBLE (-223 2950);
FORCEADD TAP..1
R 2
(-225 3050);
FORCEPROP 3 LASTPIN (-175 3050) SIG_NAME M_F_CPU0_SA_DQ<15>
J 0
(-165 3060);
DISPLAY 0.659574 (-165 3060);
PAINT MONO (-165 3060);
DISPLAY INVISIBLE (-165 3060);
FORCEPROP 1 LASTPIN (-175 3050) BN 15
J 2
(-163 3058);
DISPLAY 0.680851 (-163 3058);
PAINT GREEN (-163 3058);
FORCEPROP 2 LAST CDS_LIB standard
J 0
(-225 3050);
DISPLAY INVISIBLE (-225 3050);
FORCEPROP 1 LAST BODY_TYPE PLUMBING
J 2
(-225 3100);
DISPLAY 0.872340 (-225 3100);
PAINT GREEN (-225 3100);
DISPLAY INVISIBLE (-225 3100);
FORCEPROP 1 LAST HDL_TAP TRUE
J 2
(-550 2925);
DISPLAY 0.872340 (-550 2925);
DISPLAY INVISIBLE (-550 2925);
FORCEPROP 1 LAST PATH I75
J 2
(-223 3050);
DISPLAY 0.872340 (-223 3050);
PAINT GREEN (-223 3050);
DISPLAY INVISIBLE (-223 3050);
FORCEADD TAP..1
R 2
(-225 3150);
FORCEPROP 3 LASTPIN (-175 3150) SIG_NAME M_F_CPU0_SA_DQ<17>
J 0
(-165 3160);
DISPLAY 0.659574 (-165 3160);
PAINT MONO (-165 3160);
DISPLAY INVISIBLE (-165 3160);
FORCEPROP 1 LASTPIN (-175 3150) BN 17
J 2
(-163 3158);
DISPLAY 0.680851 (-163 3158);
PAINT GREEN (-163 3158);
FORCEPROP 2 LAST CDS_LIB standard
J 0
(-225 3150);
DISPLAY INVISIBLE (-225 3150);
FORCEPROP 1 LAST BODY_TYPE PLUMBING
J 2
(-225 3200);
DISPLAY 0.872340 (-225 3200);
PAINT GREEN (-225 3200);
DISPLAY INVISIBLE (-225 3200);
FORCEPROP 1 LAST HDL_TAP TRUE
J 2
(-550 3025);
DISPLAY 0.872340 (-550 3025);
DISPLAY INVISIBLE (-550 3025);
FORCEPROP 1 LAST PATH I76
J 2
(-223 3150);
DISPLAY 0.872340 (-223 3150);
PAINT GREEN (-223 3150);
DISPLAY INVISIBLE (-223 3150);
FORCEADD TAP..1
R 2
(-225 3100);
FORCEPROP 3 LASTPIN (-175 3100) SIG_NAME M_F_CPU0_SA_DQ<16>
J 0
(-165 3110);
DISPLAY 0.659574 (-165 3110);
PAINT MONO (-165 3110);
DISPLAY INVISIBLE (-165 3110);
FORCEPROP 1 LASTPIN (-175 3100) BN 16
J 2
(-163 3108);
DISPLAY 0.680851 (-163 3108);
PAINT GREEN (-163 3108);
FORCEPROP 2 LAST CDS_LIB standard
J 0
(-225 3100);
DISPLAY INVISIBLE (-225 3100);
FORCEPROP 1 LAST BODY_TYPE PLUMBING
J 2
(-225 3150);
DISPLAY 0.872340 (-225 3150);
PAINT GREEN (-225 3150);
DISPLAY INVISIBLE (-225 3150);
FORCEPROP 1 LAST HDL_TAP TRUE
J 2
(-550 2975);
DISPLAY 0.872340 (-550 2975);
DISPLAY INVISIBLE (-550 2975);
FORCEPROP 1 LAST PATH I77
J 2
(-223 3100);
DISPLAY 0.872340 (-223 3100);
PAINT GREEN (-223 3100);
DISPLAY INVISIBLE (-223 3100);
FORCEADD TAP..1
R 2
(-225 3200);
FORCEPROP 3 LASTPIN (-175 3200) SIG_NAME M_F_CPU0_SA_DQ<18>
J 0
(-165 3210);
DISPLAY 0.659574 (-165 3210);
PAINT MONO (-165 3210);
DISPLAY INVISIBLE (-165 3210);
FORCEPROP 1 LASTPIN (-175 3200) BN 18
J 2
(-163 3208);
DISPLAY 0.680851 (-163 3208);
PAINT GREEN (-163 3208);
FORCEPROP 2 LAST CDS_LIB standard
J 0
(-225 3200);
DISPLAY INVISIBLE (-225 3200);
FORCEPROP 1 LAST BODY_TYPE PLUMBING
J 2
(-225 3250);
DISPLAY 0.872340 (-225 3250);
PAINT GREEN (-225 3250);
DISPLAY INVISIBLE (-225 3250);
FORCEPROP 1 LAST HDL_TAP TRUE
J 2
(-550 3075);
DISPLAY 0.872340 (-550 3075);
DISPLAY INVISIBLE (-550 3075);
FORCEPROP 1 LAST PATH I78
J 2
(-223 3200);
DISPLAY 0.872340 (-223 3200);
PAINT GREEN (-223 3200);
DISPLAY INVISIBLE (-223 3200);
FORCEADD TAP..1
R 2
(-225 3250);
FORCEPROP 3 LASTPIN (-175 3250) SIG_NAME M_F_CPU0_SA_DQ<19>
J 0
(-165 3260);
DISPLAY 0.659574 (-165 3260);
PAINT MONO (-165 3260);
DISPLAY INVISIBLE (-165 3260);
FORCEPROP 1 LASTPIN (-175 3250) BN 19
J 2
(-163 3258);
DISPLAY 0.680851 (-163 3258);
PAINT GREEN (-163 3258);
FORCEPROP 2 LAST CDS_LIB standard
J 0
(-225 3250);
DISPLAY INVISIBLE (-225 3250);
FORCEPROP 1 LAST BODY_TYPE PLUMBING
J 2
(-225 3300);
DISPLAY 0.872340 (-225 3300);
PAINT GREEN (-225 3300);
DISPLAY INVISIBLE (-225 3300);
FORCEPROP 1 LAST HDL_TAP TRUE
J 2
(-550 3125);
DISPLAY 0.872340 (-550 3125);
DISPLAY INVISIBLE (-550 3125);
FORCEPROP 1 LAST PATH I79
J 2
(-223 3250);
DISPLAY 0.872340 (-223 3250);
PAINT GREEN (-223 3250);
DISPLAY INVISIBLE (-223 3250);
FORCEADD OFFPAGE..3
R 2
(-1250 275);
FORCEPROP 2 LAST $XR1 93 
J 0
(-1619 275);
DISPLAY 0.638298 (-1619 275);
PAINT MONO (-1619 275);
FORCEPROP 2 LAST $XR0 92 
J 0
(-1529 275);
DISPLAY 0.638298 (-1529 275);
PAINT MONO (-1529 275);
FORCEPROP 2 LAST CDS_LIB standard
J 0
(-1250 275);
DISPLAY INVISIBLE (-1250 275);
FORCEPROP 1 LAST OFFPAGE TRUE
J 2
(-1575 150);
DISPLAY 0.872340 (-1575 150);
DISPLAY INVISIBLE (-1575 150);
FORCEPROP 1 LAST COMMENT_BODY TRUE
J 2
(-1200 175);
DISPLAY 0.872340 (-1200 175);
PAINT GREEN (-1200 175);
DISPLAY INVISIBLE (-1200 175);
FORCEPROP 2 LAST PATH I8
J 0
(-1200 350);
DISPLAY 1.021277 (-1200 350);
DISPLAY INVISIBLE (-1200 350);
FORCEADD TAP..1
R 2
(-225 3300);
FORCEPROP 3 LASTPIN (-175 3300) SIG_NAME M_F_CPU0_SA_DQ<20>
J 0
(-165 3310);
DISPLAY 0.659574 (-165 3310);
PAINT MONO (-165 3310);
DISPLAY INVISIBLE (-165 3310);
FORCEPROP 1 LASTPIN (-175 3300) BN 20
J 2
(-163 3308);
DISPLAY 0.680851 (-163 3308);
PAINT GREEN (-163 3308);
FORCEPROP 2 LAST CDS_LIB standard
J 0
(-225 3300);
DISPLAY INVISIBLE (-225 3300);
FORCEPROP 1 LAST BODY_TYPE PLUMBING
J 2
(-225 3350);
DISPLAY 0.872340 (-225 3350);
PAINT GREEN (-225 3350);
DISPLAY INVISIBLE (-225 3350);
FORCEPROP 1 LAST HDL_TAP TRUE
J 2
(-550 3175);
DISPLAY 0.872340 (-550 3175);
DISPLAY INVISIBLE (-550 3175);
FORCEPROP 1 LAST PATH I80
J 2
(-223 3300);
DISPLAY 0.872340 (-223 3300);
PAINT GREEN (-223 3300);
DISPLAY INVISIBLE (-223 3300);
FORCEADD TAP..1
R 2
(-225 3400);
FORCEPROP 3 LASTPIN (-175 3400) SIG_NAME M_F_CPU0_SA_DQ<22>
J 0
(-165 3410);
DISPLAY 0.659574 (-165 3410);
PAINT MONO (-165 3410);
DISPLAY INVISIBLE (-165 3410);
FORCEPROP 1 LASTPIN (-175 3400) BN 22
J 2
(-163 3408);
DISPLAY 0.680851 (-163 3408);
PAINT GREEN (-163 3408);
FORCEPROP 2 LAST CDS_LIB standard
J 0
(-225 3400);
DISPLAY INVISIBLE (-225 3400);
FORCEPROP 1 LAST BODY_TYPE PLUMBING
J 2
(-225 3450);
DISPLAY 0.872340 (-225 3450);
PAINT GREEN (-225 3450);
DISPLAY INVISIBLE (-225 3450);
FORCEPROP 1 LAST HDL_TAP TRUE
J 2
(-550 3275);
DISPLAY 0.872340 (-550 3275);
DISPLAY INVISIBLE (-550 3275);
FORCEPROP 1 LAST PATH I81
J 2
(-223 3400);
DISPLAY 0.872340 (-223 3400);
PAINT GREEN (-223 3400);
DISPLAY INVISIBLE (-223 3400);
FORCEADD TAP..1
R 2
(-225 3350);
FORCEPROP 3 LASTPIN (-175 3350) SIG_NAME M_F_CPU0_SA_DQ<21>
J 0
(-165 3360);
DISPLAY 0.659574 (-165 3360);
PAINT MONO (-165 3360);
DISPLAY INVISIBLE (-165 3360);
FORCEPROP 1 LASTPIN (-175 3350) BN 21
J 2
(-163 3358);
DISPLAY 0.680851 (-163 3358);
PAINT GREEN (-163 3358);
FORCEPROP 2 LAST CDS_LIB standard
J 0
(-225 3350);
DISPLAY INVISIBLE (-225 3350);
FORCEPROP 1 LAST BODY_TYPE PLUMBING
J 2
(-225 3400);
DISPLAY 0.872340 (-225 3400);
PAINT GREEN (-225 3400);
DISPLAY INVISIBLE (-225 3400);
FORCEPROP 1 LAST HDL_TAP TRUE
J 2
(-550 3225);
DISPLAY 0.872340 (-550 3225);
DISPLAY INVISIBLE (-550 3225);
FORCEPROP 1 LAST PATH I82
J 2
(-223 3350);
DISPLAY 0.872340 (-223 3350);
PAINT GREEN (-223 3350);
DISPLAY INVISIBLE (-223 3350);
FORCEADD TAP..1
R 2
(-225 3500);
FORCEPROP 3 LASTPIN (-175 3500) SIG_NAME M_F_CPU0_SA_DQ<24>
J 0
(-165 3510);
DISPLAY 0.659574 (-165 3510);
PAINT MONO (-165 3510);
DISPLAY INVISIBLE (-165 3510);
FORCEPROP 1 LASTPIN (-175 3500) BN 24
J 2
(-163 3508);
DISPLAY 0.680851 (-163 3508);
PAINT GREEN (-163 3508);
FORCEPROP 2 LAST CDS_LIB standard
J 0
(-225 3500);
DISPLAY INVISIBLE (-225 3500);
FORCEPROP 1 LAST BODY_TYPE PLUMBING
J 2
(-225 3550);
DISPLAY 0.872340 (-225 3550);
PAINT GREEN (-225 3550);
DISPLAY INVISIBLE (-225 3550);
FORCEPROP 1 LAST HDL_TAP TRUE
J 2
(-550 3375);
DISPLAY 0.872340 (-550 3375);
DISPLAY INVISIBLE (-550 3375);
FORCEPROP 1 LAST PATH I83
J 2
(-223 3500);
DISPLAY 0.872340 (-223 3500);
PAINT GREEN (-223 3500);
DISPLAY INVISIBLE (-223 3500);
FORCEADD TAP..1
R 2
(-225 3450);
FORCEPROP 3 LASTPIN (-175 3450) SIG_NAME M_F_CPU0_SA_DQ<23>
J 0
(-165 3460);
DISPLAY 0.659574 (-165 3460);
PAINT MONO (-165 3460);
DISPLAY INVISIBLE (-165 3460);
FORCEPROP 1 LASTPIN (-175 3450) BN 23
J 2
(-163 3458);
DISPLAY 0.680851 (-163 3458);
PAINT GREEN (-163 3458);
FORCEPROP 2 LAST CDS_LIB standard
J 0
(-225 3450);
DISPLAY INVISIBLE (-225 3450);
FORCEPROP 1 LAST BODY_TYPE PLUMBING
J 2
(-225 3500);
DISPLAY 0.872340 (-225 3500);
PAINT GREEN (-225 3500);
DISPLAY INVISIBLE (-225 3500);
FORCEPROP 1 LAST HDL_TAP TRUE
J 2
(-550 3325);
DISPLAY 0.872340 (-550 3325);
DISPLAY INVISIBLE (-550 3325);
FORCEPROP 1 LAST PATH I84
J 2
(-223 3450);
DISPLAY 0.872340 (-223 3450);
PAINT GREEN (-223 3450);
DISPLAY INVISIBLE (-223 3450);
FORCEADD TAP..1
R 2
(-225 3550);
FORCEPROP 3 LASTPIN (-175 3550) SIG_NAME M_F_CPU0_SA_DQ<25>
J 0
(-165 3560);
DISPLAY 0.659574 (-165 3560);
PAINT MONO (-165 3560);
DISPLAY INVISIBLE (-165 3560);
FORCEPROP 1 LASTPIN (-175 3550) BN 25
J 2
(-163 3558);
DISPLAY 0.680851 (-163 3558);
PAINT GREEN (-163 3558);
FORCEPROP 2 LAST CDS_LIB standard
J 0
(-225 3550);
DISPLAY INVISIBLE (-225 3550);
FORCEPROP 1 LAST BODY_TYPE PLUMBING
J 2
(-225 3600);
DISPLAY 0.872340 (-225 3600);
PAINT GREEN (-225 3600);
DISPLAY INVISIBLE (-225 3600);
FORCEPROP 1 LAST HDL_TAP TRUE
J 2
(-550 3425);
DISPLAY 0.872340 (-550 3425);
DISPLAY INVISIBLE (-550 3425);
FORCEPROP 1 LAST PATH I85
J 2
(-223 3550);
DISPLAY 0.872340 (-223 3550);
PAINT GREEN (-223 3550);
DISPLAY INVISIBLE (-223 3550);
FORCEADD TAP..1
R 2
(-225 3650);
FORCEPROP 3 LASTPIN (-175 3650) SIG_NAME M_F_CPU0_SA_DQ<27>
J 0
(-165 3660);
DISPLAY 0.659574 (-165 3660);
PAINT MONO (-165 3660);
DISPLAY INVISIBLE (-165 3660);
FORCEPROP 1 LASTPIN (-175 3650) BN 27
J 2
(-163 3658);
DISPLAY 0.680851 (-163 3658);
PAINT GREEN (-163 3658);
FORCEPROP 2 LAST CDS_LIB standard
J 0
(-225 3650);
DISPLAY INVISIBLE (-225 3650);
FORCEPROP 1 LAST BODY_TYPE PLUMBING
J 2
(-225 3700);
DISPLAY 0.872340 (-225 3700);
PAINT GREEN (-225 3700);
DISPLAY INVISIBLE (-225 3700);
FORCEPROP 1 LAST HDL_TAP TRUE
J 2
(-550 3525);
DISPLAY 0.872340 (-550 3525);
DISPLAY INVISIBLE (-550 3525);
FORCEPROP 1 LAST PATH I86
J 2
(-223 3650);
DISPLAY 0.872340 (-223 3650);
PAINT GREEN (-223 3650);
DISPLAY INVISIBLE (-223 3650);
FORCEADD TAP..1
R 2
(-225 3600);
FORCEPROP 3 LASTPIN (-175 3600) SIG_NAME M_F_CPU0_SA_DQ<26>
J 0
(-165 3610);
DISPLAY 0.659574 (-165 3610);
PAINT MONO (-165 3610);
DISPLAY INVISIBLE (-165 3610);
FORCEPROP 1 LASTPIN (-175 3600) BN 26
J 2
(-163 3608);
DISPLAY 0.680851 (-163 3608);
PAINT GREEN (-163 3608);
FORCEPROP 2 LAST CDS_LIB standard
J 0
(-225 3600);
DISPLAY INVISIBLE (-225 3600);
FORCEPROP 1 LAST BODY_TYPE PLUMBING
J 2
(-225 3650);
DISPLAY 0.872340 (-225 3650);
PAINT GREEN (-225 3650);
DISPLAY INVISIBLE (-225 3650);
FORCEPROP 1 LAST HDL_TAP TRUE
J 2
(-550 3475);
DISPLAY 0.872340 (-550 3475);
DISPLAY INVISIBLE (-550 3475);
FORCEPROP 1 LAST PATH I87
J 2
(-223 3600);
DISPLAY 0.872340 (-223 3600);
PAINT GREEN (-223 3600);
DISPLAY INVISIBLE (-223 3600);
FORCEADD TAP..1
R 2
(-225 3700);
FORCEPROP 3 LASTPIN (-175 3700) SIG_NAME M_F_CPU0_SA_DQ<28>
J 0
(-165 3710);
DISPLAY 0.659574 (-165 3710);
PAINT MONO (-165 3710);
DISPLAY INVISIBLE (-165 3710);
FORCEPROP 1 LASTPIN (-175 3700) BN 28
J 2
(-163 3708);
DISPLAY 0.680851 (-163 3708);
PAINT GREEN (-163 3708);
FORCEPROP 2 LAST CDS_LIB standard
J 0
(-225 3700);
DISPLAY INVISIBLE (-225 3700);
FORCEPROP 1 LAST BODY_TYPE PLUMBING
J 2
(-225 3750);
DISPLAY 0.872340 (-225 3750);
PAINT GREEN (-225 3750);
DISPLAY INVISIBLE (-225 3750);
FORCEPROP 1 LAST HDL_TAP TRUE
J 2
(-550 3575);
DISPLAY 0.872340 (-550 3575);
DISPLAY INVISIBLE (-550 3575);
FORCEPROP 1 LAST PATH I88
J 2
(-223 3700);
DISPLAY 0.872340 (-223 3700);
PAINT GREEN (-223 3700);
DISPLAY INVISIBLE (-223 3700);
FORCEADD TAP..1
R 2
(-225 3750);
FORCEPROP 3 LASTPIN (-175 3750) SIG_NAME M_F_CPU0_SA_DQ<29>
J 0
(-165 3760);
DISPLAY 0.659574 (-165 3760);
PAINT MONO (-165 3760);
DISPLAY INVISIBLE (-165 3760);
FORCEPROP 1 LASTPIN (-175 3750) BN 29
J 2
(-163 3758);
DISPLAY 0.680851 (-163 3758);
PAINT GREEN (-163 3758);
FORCEPROP 2 LAST CDS_LIB standard
J 0
(-225 3750);
DISPLAY INVISIBLE (-225 3750);
FORCEPROP 1 LAST BODY_TYPE PLUMBING
J 2
(-225 3800);
DISPLAY 0.872340 (-225 3800);
PAINT GREEN (-225 3800);
DISPLAY INVISIBLE (-225 3800);
FORCEPROP 1 LAST HDL_TAP TRUE
J 2
(-550 3625);
DISPLAY 0.872340 (-550 3625);
DISPLAY INVISIBLE (-550 3625);
FORCEPROP 1 LAST PATH I89
J 2
(-223 3750);
DISPLAY 0.872340 (-223 3750);
PAINT GREEN (-223 3750);
DISPLAY INVISIBLE (-223 3750);
FORCEADD OFFPAGE..3
R 2
(-1250 1875);
FORCEPROP 2 LAST $XR1 93 
J 0
(-1619 1875);
DISPLAY 0.638298 (-1619 1875);
PAINT MONO (-1619 1875);
FORCEPROP 2 LAST $XR0 92 
J 0
(-1529 1875);
DISPLAY 0.638298 (-1529 1875);
PAINT MONO (-1529 1875);
FORCEPROP 2 LAST CDS_LIB standard
J 0
(-1250 1875);
DISPLAY INVISIBLE (-1250 1875);
FORCEPROP 1 LAST OFFPAGE TRUE
J 2
(-1575 1750);
DISPLAY 0.872340 (-1575 1750);
DISPLAY INVISIBLE (-1575 1750);
FORCEPROP 1 LAST COMMENT_BODY TRUE
J 2
(-1200 1775);
DISPLAY 0.872340 (-1200 1775);
PAINT GREEN (-1200 1775);
DISPLAY INVISIBLE (-1200 1775);
FORCEPROP 2 LAST PATH I9
J 0
(-1200 1950);
DISPLAY 1.021277 (-1200 1950);
DISPLAY INVISIBLE (-1200 1950);
FORCEADD TAP..1
R 2
(-225 3800);
FORCEPROP 3 LASTPIN (-175 3800) SIG_NAME M_F_CPU0_SA_DQ<30>
J 0
(-165 3810);
DISPLAY 0.659574 (-165 3810);
PAINT MONO (-165 3810);
DISPLAY INVISIBLE (-165 3810);
FORCEPROP 1 LASTPIN (-175 3800) BN 30
J 2
(-163 3808);
DISPLAY 0.680851 (-163 3808);
PAINT GREEN (-163 3808);
FORCEPROP 2 LAST CDS_LIB standard
J 0
(-225 3800);
DISPLAY INVISIBLE (-225 3800);
FORCEPROP 1 LAST BODY_TYPE PLUMBING
J 2
(-225 3850);
DISPLAY 0.872340 (-225 3850);
PAINT GREEN (-225 3850);
DISPLAY INVISIBLE (-225 3850);
FORCEPROP 1 LAST HDL_TAP TRUE
J 2
(-550 3675);
DISPLAY 0.872340 (-550 3675);
DISPLAY INVISIBLE (-550 3675);
FORCEPROP 1 LAST PATH I90
J 2
(-223 3800);
DISPLAY 0.872340 (-223 3800);
PAINT GREEN (-223 3800);
DISPLAY INVISIBLE (-223 3800);
FORCEADD TAP..1
R 2
(-225 3850);
FORCEPROP 3 LASTPIN (-175 3850) SIG_NAME M_F_CPU0_SA_DQ<31>
J 0
(-165 3860);
DISPLAY 0.659574 (-165 3860);
PAINT MONO (-165 3860);
DISPLAY INVISIBLE (-165 3860);
FORCEPROP 1 LASTPIN (-175 3850) BN 31
J 2
(-163 3858);
DISPLAY 0.680851 (-163 3858);
PAINT GREEN (-163 3858);
FORCEPROP 2 LAST CDS_LIB standard
J 0
(-225 3850);
DISPLAY INVISIBLE (-225 3850);
FORCEPROP 1 LAST BODY_TYPE PLUMBING
J 2
(-225 3900);
DISPLAY 0.872340 (-225 3900);
PAINT GREEN (-225 3900);
DISPLAY INVISIBLE (-225 3900);
FORCEPROP 1 LAST HDL_TAP TRUE
J 2
(-550 3725);
DISPLAY 0.872340 (-550 3725);
DISPLAY INVISIBLE (-550 3725);
FORCEPROP 1 LAST PATH I91
J 2
(-223 3850);
DISPLAY 0.872340 (-223 3850);
PAINT GREEN (-223 3850);
DISPLAY INVISIBLE (-223 3850);
FORCEADD OFFPAGE..4
(4300 -350);
FORCEPROP 2 LAST $XR1 93 
J 0
(4576 -350);
DISPLAY 0.638298 (4576 -350);
PAINT MONO (4576 -350);
FORCEPROP 2 LAST $XR0 92 
J 0
(4486 -350);
DISPLAY 0.638298 (4486 -350);
PAINT MONO (4486 -350);
FORCEPROP 2 LAST CDS_LIB standard
J 0
(4300 -350);
PAINT MONO (4300 -350);
DISPLAY INVISIBLE (4300 -350);
FORCEPROP 1 LAST OFFPAGE TRUE
J 0
(4625 -475);
DISPLAY 1.170213 (4625 -475);
PAINT GREEN (4625 -475);
DISPLAY INVISIBLE (4625 -475);
FORCEPROP 1 LAST COMMENT_BODY TRUE
J 0
(4275 -450);
DISPLAY 1.170213 (4275 -450);
PAINT GREEN (4275 -450);
DISPLAY INVISIBLE (4275 -450);
FORCEPROP 2 LAST PATH I92
J 0
(4475 -275);
DISPLAY 1.021277 (4475 -275);
DISPLAY INVISIBLE (4475 -275);
FORCEADD OFFPAGE..4
(4300 -250);
FORCEPROP 2 LAST $XR0 92 
J 0
(4486 -250);
DISPLAY 0.638298 (4486 -250);
PAINT MONO (4486 -250);
FORCEPROP 2 LAST CDS_LIB standard
J 0
(4300 -250);
PAINT MONO (4300 -250);
DISPLAY INVISIBLE (4300 -250);
FORCEPROP 1 LAST OFFPAGE TRUE
J 0
(4625 -375);
DISPLAY 1.170213 (4625 -375);
PAINT GREEN (4625 -375);
DISPLAY INVISIBLE (4625 -375);
FORCEPROP 1 LAST COMMENT_BODY TRUE
J 0
(4275 -350);
DISPLAY 1.170213 (4275 -350);
PAINT GREEN (4275 -350);
DISPLAY INVISIBLE (4275 -350);
FORCEPROP 2 LAST PATH I93
J 0
(4475 -175);
DISPLAY 1.021277 (4475 -175);
DISPLAY INVISIBLE (4475 -175);
FORCEADD OFFPAGE..4
(4300 -200);
FORCEPROP 2 LAST $XR0 93 
J 0
(4486 -200);
DISPLAY 0.638298 (4486 -200);
PAINT MONO (4486 -200);
FORCEPROP 2 LAST CDS_LIB standard
J 0
(4300 -200);
PAINT MONO (4300 -200);
DISPLAY INVISIBLE (4300 -200);
FORCEPROP 1 LAST OFFPAGE TRUE
J 0
(4625 -325);
DISPLAY 1.170213 (4625 -325);
PAINT GREEN (4625 -325);
DISPLAY INVISIBLE (4625 -325);
FORCEPROP 1 LAST COMMENT_BODY TRUE
J 0
(4275 -300);
DISPLAY 1.170213 (4275 -300);
PAINT GREEN (4275 -300);
DISPLAY INVISIBLE (4275 -300);
FORCEPROP 2 LAST PATH I94
J 0
(4475 -125);
DISPLAY 1.021277 (4475 -125);
DISPLAY INVISIBLE (4475 -125);
FORCEADD TAP..1
(3200 100);
FORCEPROP 3 LASTPIN (3150 100) SIG_NAME M_F_CPU0_SB_CS_N<0>
J 0
(3160 110);
DISPLAY 0.659574 (3160 110);
PAINT MONO (3160 110);
DISPLAY INVISIBLE (3160 110);
FORCEPROP 1 LASTPIN (3150 100) BN 0
J 0
(3138 108);
DISPLAY 0.680851 (3138 108);
PAINT GREEN (3138 108);
FORCEPROP 2 LAST CDS_LIB standard
J 0
(3200 100);
DISPLAY INVISIBLE (3200 100);
FORCEPROP 1 LAST BODY_TYPE PLUMBING
J 0
(3200 150);
DISPLAY 0.872340 (3200 150);
PAINT GREEN (3200 150);
DISPLAY INVISIBLE (3200 150);
FORCEPROP 1 LAST HDL_TAP TRUE
J 0
(3525 -25);
DISPLAY 0.872340 (3525 -25);
DISPLAY INVISIBLE (3525 -25);
FORCEPROP 1 LAST PATH I95
J 0
(3198 100);
DISPLAY 0.872340 (3198 100);
PAINT GREEN (3198 100);
DISPLAY INVISIBLE (3198 100);
FORCEADD TAP..1
(3200 200);
FORCEPROP 3 LASTPIN (3150 200) SIG_NAME M_F_CPU0_SB_CS_N<2>
J 0
(3160 210);
DISPLAY 0.659574 (3160 210);
PAINT MONO (3160 210);
DISPLAY INVISIBLE (3160 210);
FORCEPROP 1 LASTPIN (3150 200) BN 2
J 0
(3138 208);
DISPLAY 0.680851 (3138 208);
PAINT GREEN (3138 208);
FORCEPROP 2 LAST CDS_LIB standard
J 0
(3200 200);
DISPLAY INVISIBLE (3200 200);
FORCEPROP 1 LAST BODY_TYPE PLUMBING
J 0
(3200 250);
DISPLAY 0.872340 (3200 250);
PAINT GREEN (3200 250);
DISPLAY INVISIBLE (3200 250);
FORCEPROP 1 LAST HDL_TAP TRUE
J 0
(3525 75);
DISPLAY 0.872340 (3525 75);
DISPLAY INVISIBLE (3525 75);
FORCEPROP 1 LAST PATH I96
J 0
(3198 200);
DISPLAY 0.872340 (3198 200);
PAINT GREEN (3198 200);
DISPLAY INVISIBLE (3198 200);
FORCEADD TAP..1
(3200 150);
FORCEPROP 3 LASTPIN (3150 150) SIG_NAME M_F_CPU0_SB_CS_N<1>
J 0
(3160 160);
DISPLAY 0.659574 (3160 160);
PAINT MONO (3160 160);
DISPLAY INVISIBLE (3160 160);
FORCEPROP 1 LASTPIN (3150 150) BN 1
J 0
(3138 158);
DISPLAY 0.680851 (3138 158);
PAINT GREEN (3138 158);
FORCEPROP 2 LAST CDS_LIB standard
J 0
(3200 150);
DISPLAY INVISIBLE (3200 150);
FORCEPROP 1 LAST BODY_TYPE PLUMBING
J 0
(3200 200);
DISPLAY 0.872340 (3200 200);
PAINT GREEN (3200 200);
DISPLAY INVISIBLE (3200 200);
FORCEPROP 1 LAST HDL_TAP TRUE
J 0
(3525 25);
DISPLAY 0.872340 (3525 25);
DISPLAY INVISIBLE (3525 25);
FORCEPROP 1 LAST PATH I97
J 0
(3198 150);
DISPLAY 0.872340 (3198 150);
PAINT GREEN (3198 150);
DISPLAY INVISIBLE (3198 150);
FORCEADD TAP..1
(3200 250);
FORCEPROP 3 LASTPIN (3150 250) SIG_NAME M_F_CPU0_SB_CS_N<3>
J 0
(3160 260);
DISPLAY 0.659574 (3160 260);
PAINT MONO (3160 260);
DISPLAY INVISIBLE (3160 260);
FORCEPROP 1 LASTPIN (3150 250) BN 3
J 0
(3138 258);
DISPLAY 0.680851 (3138 258);
PAINT GREEN (3138 258);
FORCEPROP 2 LAST CDS_LIB standard
J 0
(3200 250);
DISPLAY INVISIBLE (3200 250);
FORCEPROP 1 LAST BODY_TYPE PLUMBING
J 0
(3200 300);
DISPLAY 0.872340 (3200 300);
PAINT GREEN (3200 300);
DISPLAY INVISIBLE (3200 300);
FORCEPROP 1 LAST HDL_TAP TRUE
J 0
(3525 125);
DISPLAY 0.872340 (3525 125);
DISPLAY INVISIBLE (3525 125);
FORCEPROP 1 LAST PATH I98
J 0
(3198 250);
DISPLAY 0.872340 (3198 250);
PAINT GREEN (3198 250);
DISPLAY INVISIBLE (3198 250);
FORCEADD TAP..1
(3200 400);
FORCEPROP 3 LASTPIN (3150 400) SIG_NAME M_F_CPU0_SA_CS_N<0>
J 0
(3160 410);
DISPLAY 0.659574 (3160 410);
PAINT MONO (3160 410);
DISPLAY INVISIBLE (3160 410);
FORCEPROP 1 LASTPIN (3150 400) BN 0
J 0
(3138 408);
DISPLAY 0.680851 (3138 408);
PAINT GREEN (3138 408);
FORCEPROP 2 LAST CDS_LIB standard
J 0
(3200 400);
DISPLAY INVISIBLE (3200 400);
FORCEPROP 1 LAST BODY_TYPE PLUMBING
J 0
(3200 450);
DISPLAY 0.872340 (3200 450);
PAINT GREEN (3200 450);
DISPLAY INVISIBLE (3200 450);
FORCEPROP 1 LAST HDL_TAP TRUE
J 0
(3525 275);
DISPLAY 0.872340 (3525 275);
DISPLAY INVISIBLE (3525 275);
FORCEPROP 1 LAST PATH I99
J 0
(3198 400);
DISPLAY 0.872340 (3198 400);
PAINT GREEN (3198 400);
DISPLAY INVISIBLE (3198 400);
FORCEADD QUANTA_TITLE_BLOCK_C..1
(6125 -1650);
FORCEPROP 0 LAST CDS_CON_LAST_MODIFIED Fri Aug 25 14:00:10 2023
J 0
(4240 -1635);
PAINT MONO (4240 -1635);
DISPLAY INVISIBLE (4240 -1635);
FORCEPROP 1 LAST CUSTOM_TXT_CDS <CON_LAST_MODIFIED>
J 0
(4240 -1635);
DISPLAY 0.978723 (4240 -1635);
FORCEPROP 2 LAST CUSTOM_TXT_CDS <XR_PAGE_TITLE>
J 0
(-1765 3600);
DISPLAY 0.638298 (-1765 3600);
PAINT PINK (-1765 3600);
DISPLAY INVISIBLE (-1765 3600);
FORCEPROP 2 LAST CUSTOM_TXT_CDS <Q_NUMBER>
J 0
(4722 -1547);
DISPLAY 1.212766 (4722 -1547);
FORCEPROP 2 LAST CUSTOM_TXT_CDS 01
J 0
(5941 -1547);
DISPLAY 1.212766 (5941 -1547);
FORCEPROP 1 LAST CUSTOM_TXT_CDS <NAME_2>
J 0
(2950 -1600);
FORCEPROP 1 LAST CUSTOM_TXT_CDS <NAME_1>
J 0
(2950 -1475);
FORCEPROP 1 LAST CUSTOM_TXT_CDS <Q_PROJ>
J 0
(3743 -1548);
DISPLAY 1.212766 (3743 -1548);
FORCEPROP 1 LAST CUSTOM_TXT_CDS <Q_REV>
J 0
(5941 -1547);
DISPLAY 1.212766 (5941 -1547);
FORCEPROP 1 LAST CUSTOM_TXT_CDS <CON_PAGE_NUM> OF <CON_TOTAL_PAGES>
J 0
(5679 -1632);
DISPLAY 0.978723 (5679 -1632);
FORCEPROP 1 LAST Q_TITLE SPR CPU0 - DDR CH F (13 OF 30)
J 0
(-3241 -1624);
DISPLAY 1.957447 (-3241 -1624);
PAINT GREEN (-3241 -1624);
FORCEPROP 1 LAST Q_DEPT 
J 1
(2362 -1601);
DISPLAY 1.957447 (2362 -1601);
PAINT GREEN (2362 -1601);
FORCEPROP 2 LAST CDS_LIB pure_quanta
J 0
(6125 -1650);
PAINT MONO (6125 -1650);
DISPLAY INVISIBLE (6125 -1650);
FORCEPROP 1 LAST CDS_LMAN_SYM_OUTLINE -9475,6775,100,-125
J 0
(6125 -1650);
DISPLAY 0.468085 (6125 -1650);
PAINT GREEN (6125 -1650);
DISPLAY INVISIBLE (6125 -1650);
FORCEPROP 2 LAST PAGE_BORDER TRUE
J 0
(-1765 3600);
DISPLAY 0.638298 (-1765 3600);
PAINT PINK (-1765 3600);
DISPLAY INVISIBLE (-1765 3600);
FORCEPROP 2 LAST CDS_XR_PAGE_TITLE CR-25 : @S9S_MB_2U_LIB.S9S_MB_2U(SCH_1):PAGE25
J 0
(-1765 3600);
DISPLAY 0.638298 (-1765 3600);
PAINT PINK (-1765 3600);
DISPLAY INVISIBLE (-1765 3600);
FORCEPROP 1 LAST COMMENT_BODY TRUE
J 0
(6137 -1663);
DISPLAY 0.978723 (6137 -1663);
PAINT GREEN (6137 -1663);
DISPLAY INVISIBLE (6137 -1663);
WIRE 17 -1 (3250 1525)(3250 1575);
WIRE 17 -1 (3250 1475)(3250 1525);
WIRE 17 -1 (3250 1575)(4250 1575);
FORCEPROP 2 LAST SIG_NAME M_F_CPU0_SA_CA<6:0>
J 0
(3390 1585);
DISPLAY 0.680851 (3390 1585);
PAINT WHITE (3390 1585);
WIRE 17 -1 (3250 1425)(3250 1475);
WIRE 17 -1 (3250 1375)(3250 1425);
WIRE 17 -1 (3250 1325)(3250 1375);
WIRE 17 -1 (3250 1275)(3250 1325);
WIRE 17 -1 (3250 525)(3250 575);
WIRE 17 -1 (3250 475)(3250 525);
WIRE 17 -1 (3250 575)(4250 575);
FORCEPROP 2 LAST SIG_NAME M_F_CPU0_SA_CS_N<3:0>
J 0
(3390 585);
DISPLAY 0.680851 (3390 585);
PAINT WHITE (3390 585);
WIRE 17 -1 (3250 425)(3250 475);
WIRE 17 -1 (3250 3275)(3250 3325);
WIRE 17 -1 (3250 3225)(3250 3275);
WIRE 17 -1 (3250 3325)(4250 3325);
FORCEPROP 2 LAST SIG_NAME M_F_CPU0_SA_DQS_DN<9:0>
J 0
(3390 3335);
DISPLAY 0.680851 (3390 3335);
PAINT WHITE (3390 3335);
WIRE 17 -1 (3250 3175)(3250 3225);
WIRE 17 -1 (3250 3125)(3250 3175);
WIRE 17 -1 (3250 3075)(3250 3125);
WIRE 17 -1 (3250 3025)(3250 3075);
WIRE 17 -1 (3250 2975)(3250 3025);
WIRE 17 -1 (3250 2925)(3250 2975);
WIRE 17 -1 (3250 2875)(3250 2925);
WIRE 17 -1 (3250 3825)(3250 3875);
WIRE 17 -1 (3250 3775)(3250 3825);
WIRE 17 -1 (3250 3875)(4250 3875);
FORCEPROP 2 LAST SIG_NAME M_F_CPU0_SA_DQS_DP<9:0>
J 0
(3390 3885);
DISPLAY 0.680851 (3390 3885);
PAINT WHITE (3390 3885);
WIRE 17 -1 (3250 3725)(3250 3775);
WIRE 17 -1 (3250 3675)(3250 3725);
WIRE 17 -1 (3250 3625)(3250 3675);
WIRE 17 -1 (3250 3575)(3250 3625);
WIRE 17 -1 (3250 3525)(3250 3575);
WIRE 17 -1 (3250 3475)(3250 3525);
WIRE 17 -1 (3250 3425)(3250 3475);
WIRE 17 -1 (3250 1025)(3250 1075);
WIRE 17 -1 (3250 975)(3250 1025);
WIRE 17 -1 (3250 1075)(4250 1075);
FORCEPROP 2 LAST SIG_NAME M_F_CPU0_SB_CA<6:0>
J 0
(3390 1085);
DISPLAY 0.680851 (3390 1085);
PAINT WHITE (3390 1085);
WIRE 17 -1 (3250 925)(3250 975);
WIRE 17 -1 (3250 875)(3250 925);
WIRE 17 -1 (3250 825)(3250 875);
WIRE 17 -1 (3250 775)(3250 825);
WIRE 17 -1 (3250 225)(3250 275);
WIRE 17 -1 (3250 175)(3250 225);
WIRE 17 -1 (3250 275)(4250 275);
FORCEPROP 2 LAST SIG_NAME M_F_CPU0_SB_CS_N<3:0>
J 0
(3390 285);
DISPLAY 0.680851 (3390 285);
PAINT WHITE (3390 285);
WIRE 17 -1 (3250 125)(3250 175);
WIRE 17 -1 (3250 2125)(3250 2175);
WIRE 17 -1 (3250 2075)(3250 2125);
WIRE 17 -1 (3250 2175)(4250 2175);
FORCEPROP 2 LAST SIG_NAME M_F_CPU0_SB_DQS_DN<9:0>
J 0
(3390 2185);
DISPLAY 0.680851 (3390 2185);
PAINT WHITE (3390 2185);
WIRE 17 -1 (3250 2025)(3250 2075);
WIRE 17 -1 (3250 1975)(3250 2025);
WIRE 17 -1 (3250 1925)(3250 1975);
WIRE 17 -1 (3250 1875)(3250 1925);
WIRE 17 -1 (3250 1825)(3250 1875);
WIRE 17 -1 (3250 1775)(3250 1825);
WIRE 17 -1 (3250 1725)(3250 1775);
WIRE 17 -1 (3250 2675)(3250 2725);
WIRE 17 -1 (3250 2625)(3250 2675);
WIRE 17 -1 (3250 2725)(4250 2725);
FORCEPROP 2 LAST SIG_NAME M_F_CPU0_SB_DQS_DP<9:0>
J 0
(3390 2735);
DISPLAY 0.680851 (3390 2735);
PAINT WHITE (3390 2735);
WIRE 17 -1 (3250 2575)(3250 2625);
WIRE 17 -1 (3250 2525)(3250 2575);
WIRE 17 -1 (3250 2475)(3250 2525);
WIRE 17 -1 (3250 2425)(3250 2475);
WIRE 17 -1 (3250 2375)(3250 2425);
WIRE 17 -1 (3250 2325)(3250 2375);
WIRE 17 -1 (3250 2275)(3250 2325);
WIRE 17 -1 (-275 -75)(-275 -25);
WIRE 17 -1 (-275 -25)(-275 25);
WIRE 17 -1 (-275 25)(-275 75);
WIRE 17 -1 (-275 75)(-275 125);
WIRE 17 -1 (-275 125)(-275 175);
WIRE 17 -1 (-275 175)(-275 225);
WIRE 17 -1 (-275 225)(-275 275);
WIRE 17 -1 (-1200 275)(-275 275);
FORCEPROP 2 LAST SIG_NAME M_F_CPU0_SB_CB<7:0>
J 0
(-1060 285);
DISPLAY 0.680851 (-1060 285);
PAINT WHITE (-1060 285);
WIRE 17 -1 (-275 325)(-275 375);
WIRE 17 -1 (-275 375)(-275 425);
WIRE 17 -1 (-275 425)(-275 475);
WIRE 17 -1 (-275 475)(-275 525);
WIRE 17 -1 (-275 525)(-275 575);
WIRE 17 -1 (-275 575)(-275 625);
WIRE 17 -1 (-275 625)(-275 675);
WIRE 17 -1 (-275 675)(-275 725);
WIRE 17 -1 (-275 725)(-275 775);
WIRE 17 -1 (-275 775)(-275 825);
WIRE 17 -1 (-275 825)(-275 875);
WIRE 17 -1 (-275 875)(-275 925);
WIRE 17 -1 (-275 925)(-275 975);
WIRE 17 -1 (-275 975)(-275 1025);
WIRE 17 -1 (-275 1025)(-275 1075);
WIRE 17 -1 (-275 1075)(-275 1125);
WIRE 17 -1 (-275 1125)(-275 1175);
WIRE 17 -1 (-275 1175)(-275 1225);
WIRE 17 -1 (-275 1225)(-275 1275);
WIRE 17 -1 (-275 1275)(-275 1325);
WIRE 17 -1 (-275 1325)(-275 1375);
WIRE 17 -1 (-275 1375)(-275 1425);
WIRE 17 -1 (-275 1425)(-275 1475);
WIRE 17 -1 (-275 1475)(-275 1525);
WIRE 17 -1 (-275 1525)(-275 1575);
WIRE 17 -1 (-275 1575)(-275 1625);
WIRE 17 -1 (-275 1625)(-275 1675);
WIRE 17 -1 (-275 1675)(-275 1725);
WIRE 17 -1 (-275 1725)(-275 1775);
WIRE 17 -1 (-275 1775)(-275 1825);
WIRE 17 -1 (-275 1825)(-275 1875);
WIRE 17 -1 (-1200 1875)(-275 1875);
FORCEPROP 2 LAST SIG_NAME M_F_CPU0_SB_DQ<31:0>
J 0
(-1060 1885);
DISPLAY 0.680851 (-1060 1885);
PAINT WHITE (-1060 1885);
WIRE 17 -1 (-275 1925)(-275 1975);
WIRE 17 -1 (-275 1975)(-275 2025);
WIRE 17 -1 (-275 2025)(-275 2075);
WIRE 17 -1 (-275 2075)(-275 2125);
WIRE 17 -1 (-275 2125)(-275 2175);
WIRE 17 -1 (-275 2175)(-275 2225);
WIRE 17 -1 (-275 2225)(-275 2275);
WIRE 17 -1 (-1200 2275)(-275 2275);
FORCEPROP 2 LAST SIG_NAME M_F_CPU0_SA_CB<7:0>
J 0
(-1060 2285);
DISPLAY 0.680851 (-1060 2285);
PAINT WHITE (-1060 2285);
WIRE 17 -1 (-275 2325)(-275 2375);
WIRE 17 -1 (-275 2375)(-275 2425);
WIRE 17 -1 (-275 2425)(-275 2475);
WIRE 17 -1 (-275 2475)(-275 2525);
WIRE 17 -1 (-275 2525)(-275 2575);
WIRE 17 -1 (-275 2575)(-275 2625);
WIRE 17 -1 (-275 2625)(-275 2675);
WIRE 17 -1 (-275 2675)(-275 2725);
WIRE 17 -1 (-275 2725)(-275 2775);
WIRE 17 -1 (-275 2775)(-275 2825);
WIRE 17 -1 (-275 2825)(-275 2875);
WIRE 17 -1 (-275 2875)(-275 2925);
WIRE 17 -1 (-275 2925)(-275 2975);
WIRE 17 -1 (-275 2975)(-275 3025);
WIRE 17 -1 (-275 3025)(-275 3075);
WIRE 17 -1 (-275 3075)(-275 3125);
WIRE 17 -1 (-275 3125)(-275 3175);
WIRE 17 -1 (-275 3175)(-275 3225);
WIRE 17 -1 (-275 3225)(-275 3275);
WIRE 17 -1 (-275 3275)(-275 3325);
WIRE 17 -1 (-275 3325)(-275 3375);
WIRE 17 -1 (-275 3375)(-275 3425);
WIRE 17 -1 (-275 3425)(-275 3475);
WIRE 17 -1 (-275 3475)(-275 3525);
WIRE 17 -1 (-275 3525)(-275 3575);
WIRE 17 -1 (-275 3575)(-275 3625);
WIRE 17 -1 (-275 3625)(-275 3675);
WIRE 17 -1 (-275 3675)(-275 3725);
WIRE 17 -1 (-275 3725)(-275 3775);
WIRE 17 -1 (-275 3775)(-275 3825);
WIRE 17 -1 (-275 3825)(-275 3875);
WIRE 17 -1 (-1200 3875)(-275 3875);
FORCEPROP 2 LAST SIG_NAME M_F_CPU0_SA_DQ<31:0>
J 0
(-1060 3885);
DISPLAY 0.680851 (-1060 3885);
PAINT WHITE (-1060 3885);
WIRE 17 -1 (-275 -225)(-275 -175);
WIRE 17 -1 (-1200 -175)(-275 -175);
FORCEPROP 2 LAST SIG_NAME M_F_CPU0_CLK_DP<1:0>
J 0
(-1060 -165);
DISPLAY 0.680851 (-1060 -165);
PAINT WHITE (-1060 -165);
WIRE 17 -1 (-275 -325)(-275 -275);
WIRE 17 -1 (-1200 -275)(-275 -275);
FORCEPROP 2 LAST SIG_NAME M_F_CPU0_CLK_DN<1:0>
J 0
(-1060 -265);
DISPLAY 0.680851 (-1060 -265);
PAINT WHITE (-1060 -265);
WIRE 16 -1 (-175 -300)(275 -300);
WIRE 16 -1 (-175 -350)(275 -350);
WIRE 16 -1 (-175 -200)(275 -200);
WIRE 16 -1 (-175 -250)(275 -250);
WIRE 16 -1 (-175 3850)(275 3850);
WIRE 16 -1 (-175 3800)(275 3800);
WIRE 16 -1 (-175 3750)(275 3750);
WIRE 16 -1 (-175 3700)(275 3700);
WIRE 16 -1 (-175 3650)(275 3650);
WIRE 16 -1 (-175 3600)(275 3600);
WIRE 16 -1 (-175 3550)(275 3550);
WIRE 16 -1 (-175 3500)(275 3500);
WIRE 16 -1 (-175 3450)(275 3450);
WIRE 16 -1 (-175 3400)(275 3400);
WIRE 16 -1 (-175 3350)(275 3350);
WIRE 16 -1 (-175 3300)(275 3300);
WIRE 16 -1 (-175 3250)(275 3250);
WIRE 16 -1 (-175 3200)(275 3200);
WIRE 16 -1 (-175 3150)(275 3150);
WIRE 16 -1 (-175 3100)(275 3100);
WIRE 16 -1 (-175 3050)(275 3050);
WIRE 16 -1 (-175 3000)(275 3000);
WIRE 16 -1 (-175 2950)(275 2950);
WIRE 16 -1 (-175 2900)(275 2900);
WIRE 16 -1 (-175 2850)(275 2850);
WIRE 16 -1 (-175 2800)(275 2800);
WIRE 16 -1 (-175 2750)(275 2750);
WIRE 16 -1 (-175 2700)(275 2700);
WIRE 16 -1 (-175 2650)(275 2650);
WIRE 16 -1 (-175 2600)(275 2600);
WIRE 16 -1 (-175 2550)(275 2550);
WIRE 16 -1 (-175 2500)(275 2500);
WIRE 16 -1 (-175 2450)(275 2450);
WIRE 16 -1 (-175 2400)(275 2400);
WIRE 16 -1 (-175 2350)(275 2350);
WIRE 16 -1 (-175 2300)(275 2300);
WIRE 16 -1 (-175 2250)(275 2250);
WIRE 16 -1 (-175 2200)(275 2200);
WIRE 16 -1 (-175 2150)(275 2150);
WIRE 16 -1 (-175 2100)(275 2100);
WIRE 16 -1 (-175 2050)(275 2050);
WIRE 16 -1 (-175 2000)(275 2000);
WIRE 16 -1 (-175 1950)(275 1950);
WIRE 16 -1 (-175 1900)(275 1900);
WIRE 16 -1 (-175 1850)(275 1850);
WIRE 16 -1 (-175 1800)(275 1800);
WIRE 16 -1 (-175 1750)(275 1750);
WIRE 16 -1 (-175 1700)(275 1700);
WIRE 16 -1 (-175 1650)(275 1650);
WIRE 16 -1 (-175 1600)(275 1600);
WIRE 16 -1 (-175 1550)(275 1550);
WIRE 16 -1 (-175 1500)(275 1500);
WIRE 16 -1 (-175 1450)(275 1450);
WIRE 16 -1 (-175 1400)(275 1400);
WIRE 16 -1 (-175 1350)(275 1350);
WIRE 16 -1 (-175 1300)(275 1300);
WIRE 16 -1 (-175 1250)(275 1250);
WIRE 16 -1 (-175 1200)(275 1200);
WIRE 16 -1 (-175 1150)(275 1150);
WIRE 16 -1 (-175 1100)(275 1100);
WIRE 16 -1 (-175 1050)(275 1050);
WIRE 16 -1 (-175 1000)(275 1000);
WIRE 16 -1 (-175 950)(275 950);
WIRE 16 -1 (-175 900)(275 900);
WIRE 16 -1 (-175 850)(275 850);
WIRE 16 -1 (-175 800)(275 800);
WIRE 16 -1 (-175 750)(275 750);
WIRE 16 -1 (-175 700)(275 700);
WIRE 16 -1 (-175 650)(275 650);
WIRE 16 -1 (-175 600)(275 600);
WIRE 16 -1 (-175 550)(275 550);
WIRE 16 -1 (-175 500)(275 500);
WIRE 16 -1 (-175 450)(275 450);
WIRE 16 -1 (-175 400)(275 400);
WIRE 16 -1 (-175 350)(275 350);
WIRE 16 -1 (-175 300)(275 300);
WIRE 16 -1 (-175 250)(275 250);
WIRE 16 -1 (-175 200)(275 200);
WIRE 16 -1 (-175 150)(275 150);
WIRE 16 -1 (-175 100)(275 100);
WIRE 16 -1 (-175 50)(275 50);
WIRE 16 -1 (-175 0)(275 0);
WIRE 16 -1 (-175 -50)(275 -50);
WIRE 16 -1 (-175 -100)(275 -100);
WIRE 16 -1 (4250 700)(2725 700);
FORCEPROP 2 LAST SIG_NAME M_F_CPU0_SB_PAR
J 0
(3359 709);
DISPLAY 0.680851 (3359 709);
PAINT WHITE (3359 709);
WIRE 16 -1 (2725 2250)(3150 2250);
WIRE 16 -1 (2725 2300)(3150 2300);
WIRE 16 -1 (2725 2350)(3150 2350);
WIRE 16 -1 (2725 2400)(3150 2400);
WIRE 16 -1 (2725 2450)(3150 2450);
WIRE 16 -1 (2725 2500)(3150 2500);
WIRE 16 -1 (2725 2550)(3150 2550);
WIRE 16 -1 (2725 2600)(3150 2600);
WIRE 16 -1 (2725 2650)(3150 2650);
WIRE 16 -1 (2725 2700)(3150 2700);
WIRE 16 -1 (2725 1700)(3150 1700);
WIRE 16 -1 (2725 1750)(3150 1750);
WIRE 16 -1 (2725 1800)(3150 1800);
WIRE 16 -1 (2725 1850)(3150 1850);
WIRE 16 -1 (2725 1900)(3150 1900);
WIRE 16 -1 (2725 1950)(3150 1950);
WIRE 16 -1 (2725 2000)(3150 2000);
WIRE 16 -1 (2725 2050)(3150 2050);
WIRE 16 -1 (2725 2100)(3150 2100);
WIRE 16 -1 (2725 2150)(3150 2150);
WIRE 16 -1 (2725 100)(3150 100);
WIRE 16 -1 (2725 150)(3150 150);
WIRE 16 -1 (2725 200)(3150 200);
WIRE 16 -1 (2725 250)(3150 250);
WIRE 16 -1 (2725 750)(3150 750);
WIRE 16 -1 (2725 800)(3150 800);
WIRE 16 -1 (2725 850)(3150 850);
WIRE 16 -1 (2725 900)(3150 900);
WIRE 16 -1 (2725 950)(3150 950);
WIRE 16 -1 (2725 1000)(3150 1000);
WIRE 16 -1 (2725 1050)(3150 1050);
WIRE 16 -1 (4250 1200)(2725 1200);
FORCEPROP 2 LAST SIG_NAME M_F_CPU0_SA_PAR
J 0
(3359 1209);
DISPLAY 0.680851 (3359 1209);
PAINT WHITE (3359 1209);
WIRE 16 -1 (2725 3400)(3150 3400);
WIRE 16 -1 (2725 3450)(3150 3450);
WIRE 16 -1 (2725 3500)(3150 3500);
WIRE 16 -1 (2725 3550)(3150 3550);
WIRE 16 -1 (2725 3600)(3150 3600);
WIRE 16 -1 (2725 3650)(3150 3650);
WIRE 16 -1 (2725 3700)(3150 3700);
WIRE 16 -1 (2725 3750)(3150 3750);
WIRE 16 -1 (2725 3800)(3150 3800);
WIRE 16 -1 (2725 3850)(3150 3850);
WIRE 16 -1 (2725 2850)(3150 2850);
WIRE 16 -1 (2725 2900)(3150 2900);
WIRE 16 -1 (2725 2950)(3150 2950);
WIRE 16 -1 (2725 3000)(3150 3000);
WIRE 16 -1 (2725 3050)(3150 3050);
WIRE 16 -1 (2725 3100)(3150 3100);
WIRE 16 -1 (2725 3150)(3150 3150);
WIRE 16 -1 (2725 3200)(3150 3200);
WIRE 16 -1 (2725 3250)(3150 3250);
WIRE 16 -1 (2725 3300)(3150 3300);
WIRE 16 -1 (2725 400)(3150 400);
WIRE 16 -1 (2725 450)(3150 450);
WIRE 16 -1 (2725 500)(3150 500);
WIRE 16 -1 (2725 550)(3150 550);
WIRE 16 -1 (2725 1250)(3150 1250);
WIRE 16 -1 (2725 1300)(3150 1300);
WIRE 16 -1 (2725 1350)(3150 1350);
WIRE 16 -1 (2725 1400)(3150 1400);
WIRE 16 -1 (2725 1450)(3150 1450);
WIRE 16 -1 (2725 1500)(3150 1500);
WIRE 16 -1 (2725 1550)(3150 1550);
WIRE 16 -1 (4250 -250)(2725 -250);
FORCEPROP 2 LAST SIG_NAME M_F_CPU0_SB_RSP<0>
J 0
(3359 -241);
DISPLAY 0.680851 (3359 -241);
PAINT WHITE (3359 -241);
WIRE 16 -1 (4250 -200)(2725 -200);
FORCEPROP 2 LAST SIG_NAME M_F_CPU0_SB_RSP<1>
J 0
(3359 -191);
DISPLAY 0.680851 (3359 -191);
PAINT WHITE (3359 -191);
WIRE 16 -1 (4250 -100)(2725 -100);
FORCEPROP 2 LAST SIG_NAME M_F_CPU0_SA_RSP<0>
J 0
(3359 -91);
DISPLAY 0.680851 (3359 -91);
PAINT WHITE (3359 -91);
WIRE 16 -1 (4250 -50)(2725 -50);
FORCEPROP 2 LAST SIG_NAME M_F_CPU0_SA_RSP<1>
J 0
(3359 -41);
DISPLAY 0.680851 (3359 -41);
PAINT WHITE (3359 -41);
WIRE 16 -1 (4250 -350)(2725 -350);
FORCEPROP 2 LAST SIG_NAME M_F_CPU0_ALERT_N
J 0
(3359 -341);
DISPLAY 0.680851 (3359 -341);
PAINT WHITE (3359 -341);
QUIT
